FILE_TYPE = MACRO_DRAWING;
SET COLOR_WIRE YELLOW;
SET COLOR_PROP MONO;
SET COLOR_DOT WHITE;
SET COLOR_ARC YELLOW;
SET COLOR_BODY GREEN;
SET COLOR_NOTE MONO;
SET PROP_DISPLAY VALUE;
SET PAGE_NUMBER P182;
FORCEADD OFFPAGE..3
(-5525 750);
FORCEPROP 2 LAST $XR0 181 
J 0
(-5311 750);
DISPLAY 0.638298 (-5311 750);
PAINT MONO (-5311 750);
FORCEPROP 1 LAST COMMENT_BODY TRUE
J 0
(-5575 650);
DISPLAY 0.872340 (-5575 650);
PAINT GREEN (-5575 650);
DISPLAY INVISIBLE (-5575 650);
FORCEPROP 2 LAST CDS_LIB mstr_standard
J 0
(-5525 750);
PAINT ORANGE (-5525 750);
DISPLAY INVISIBLE (-5525 750);
FORCEPROP 2 LAST PATH I100
J 0
(-5325 825);
DISPLAY 1.021277 (-5325 825);
PAINT ORANGE (-5325 825);
DISPLAY INVISIBLE (-5325 825);
FORCEPROP 1 LAST OFFPAGE TRUE
J 0
(-5200 625);
DISPLAY 0.872340 (-5200 625);
PAINT GREEN (-5200 625);
DISPLAY INVISIBLE (-5200 625);
FORCEADD RES..1
(-6550 750);
FORCEPROP 1 LAST WATTAGE 1/16W
J 2
(-6675 700);
DISPLAY 0.617021 (-6675 700);
PAINT SKYBLUE (-6675 700);
FORCEPROP 1 LAST LOCATION R1C10
J 2
(-6675 750);
DISPLAY 0.617021 (-6675 750);
PAINT AQUA (-6675 750);
FORCEPROP 1 LAST VALUE 0.0
J 2
(-6575 700);
DISPLAY 0.617021 (-6575 700);
PAINT SKYBLUE (-6575 700);
FORCEPROP 1 LAST TOLERANCE 5%
J 0
(-6500 700);
DISPLAY 0.617021 (-6500 700);
PAINT SKYBLUE (-6500 700);
FORCEPROP 1 LASTPIN (-6650 750) $PN 1
J 0
(-6638 762);
DISPLAY 0.617021 (-6638 762);
PAINT ORANGE (-6638 762);
FORCEPROP 1 LASTPIN (-6450 750) $PN 2
J 0
(-6488 762);
DISPLAY 0.617021 (-6488 762);
PAINT ORANGE (-6488 762);
FORCEPROP 1 LAST PART_NUMBER G21497-005
J 2
(-6200 750);
DISPLAY 0.617021 (-6200 750);
PAINT BLUE (-6200 750);
FORCEPROP 1 LAST MATERIAL EMPTY
J 0
(-6425 700);
DISPLAY 0.617021 (-6425 700);
PAINT RED (-6425 700);
FORCEPROP 1 LAST PACK_TYPE 0402
J 0
(-6300 700);
DISPLAY 0.617021 (-6300 700);
PAINT SKYBLUE (-6300 700);
FORCEPROP 2 LAST CDS_LOCATION R1C10
J 2
(-6675 750);
DISPLAY 0.617021 (-6675 750);
PAINT AQUA (-6675 750);
DISPLAY INVISIBLE (-6675 750);
FORCEPROP 2 LAST CDS_LIB mstr_discrete
J 0
(-6550 750);
PAINT ORANGE (-6550 750);
DISPLAY INVISIBLE (-6550 750);
FORCEPROP 1 LAST PATH I101
J 0
(-6600 900);
DISPLAY 0.978723 (-6600 900);
PAINT WHITE (-6600 900);
DISPLAY INVISIBLE (-6600 900);
FORCEPROP 2 LAST NO_XNET_CONNECTION 1
J 0
(-6600 950);
PAINT MONO (-6600 950);
DISPLAY INVISIBLE (-6600 950);
FORCEPROP 2 LAST SEC 1
J 0
(-6600 950);
DISPLAY 0.680851 (-6600 950);
PAINT MONO (-6600 950);
DISPLAY INVISIBLE (-6600 950);
FORCEPROP 2 LAST SEC_TYPE 0402
J 0
(-6600 950);
DISPLAY 1.021277 (-6600 950);
PAINT ORANGE (-6600 950);
DISPLAY INVISIBLE (-6600 950);
FORCEPROP 0 LAST ROOM IO_SLOT
J 0
(-6475 850);
DISPLAY 1.021277 (-6475 850);
PAINT ORANGE (-6475 850);
DISPLAY INVISIBLE (-6475 850);
FORCEADD OFFPAGE..6
(-7425 750);
FORCEPROP 2 LAST $XR0 138 
J 0
(-7705 750);
DISPLAY 0.638298 (-7705 750);
PAINT MONO (-7705 750);
FORCEPROP 2 LAST $XR1 156 
J 0
(-7825 750);
DISPLAY 0.638298 (-7825 750);
PAINT MONO (-7825 750);
FORCEPROP 2 LAST $XR2 160 
J 0
(-7945 750);
DISPLAY 0.638298 (-7945 750);
PAINT MONO (-7945 750);
FORCEPROP 2 LAST $XR3 182 
J 0
(-7705 714);
DISPLAY 0.638298 (-7705 714);
PAINT MONO (-7705 714);
FORCEPROP 2 LAST $XR5 ?
J 0
(-7705 714);
DISPLAY 0.638298 (-7705 714);
PAINT MONO (-7705 714);
FORCEPROP 2 LAST $XR4 ?
J 0
(-7705 714);
DISPLAY 0.638298 (-7705 714);
PAINT MONO (-7705 714);
FORCEPROP 2 LAST CDS_LIB mstr_standard
J 0
(-7425 750);
PAINT ORANGE (-7425 750);
DISPLAY INVISIBLE (-7425 750);
FORCEPROP 2 LAST PATH I102
J 0
(-7375 825);
DISPLAY 1.021277 (-7375 825);
PAINT ORANGE (-7375 825);
DISPLAY INVISIBLE (-7375 825);
FORCEPROP 1 LAST COMMENT_BODY TRUE
J 0
(-7325 675);
DISPLAY 0.872340 (-7325 675);
PAINT GREEN (-7325 675);
DISPLAY INVISIBLE (-7325 675);
FORCEPROP 1 LAST OFFPAGE TRUE
J 0
(-7100 625);
DISPLAY 0.872340 (-7100 625);
PAINT GREEN (-7100 625);
DISPLAY INVISIBLE (-7100 625);
FORCEADD OFFPAGE..2
(-5525 625);
FORCEPROP 2 LAST $XR0 181 
J 0
(-5336 625);
DISPLAY 0.638298 (-5336 625);
PAINT MONO (-5336 625);
FORCEPROP 1 LAST OFFPAGE TRUE
J 0
(-5200 500);
DISPLAY 0.872340 (-5200 500);
PAINT GREEN (-5200 500);
DISPLAY INVISIBLE (-5200 500);
FORCEPROP 1 LAST COMMENT_BODY TRUE
J 0
(-5570 530);
DISPLAY 0.872340 (-5570 530);
PAINT GREEN (-5570 530);
DISPLAY INVISIBLE (-5570 530);
FORCEPROP 2 LAST CDS_LIB mstr_standard
J 0
(-5525 625);
PAINT ORANGE (-5525 625);
DISPLAY INVISIBLE (-5525 625);
FORCEPROP 2 LAST PATH I103
J 0
(-5325 700);
DISPLAY 1.021277 (-5325 700);
PAINT ORANGE (-5325 700);
DISPLAY INVISIBLE (-5325 700);
FORCEADD RES..1
(-6550 625);
FORCEPROP 1 LAST LOCATION R1C9
J 2
(-6675 625);
DISPLAY 0.617021 (-6675 625);
PAINT AQUA (-6675 625);
FORCEPROP 1 LAST WATTAGE 1/16W
J 2
(-6675 575);
DISPLAY 0.617021 (-6675 575);
PAINT SKYBLUE (-6675 575);
FORCEPROP 1 LAST VALUE 0.0
J 2
(-6575 575);
DISPLAY 0.617021 (-6575 575);
PAINT SKYBLUE (-6575 575);
FORCEPROP 1 LASTPIN (-6650 625) $PN 1
J 0
(-6638 637);
DISPLAY 0.617021 (-6638 637);
PAINT ORANGE (-6638 637);
FORCEPROP 1 LAST TOLERANCE 5%
J 0
(-6500 575);
DISPLAY 0.617021 (-6500 575);
PAINT SKYBLUE (-6500 575);
FORCEPROP 1 LASTPIN (-6450 625) $PN 2
J 0
(-6488 637);
DISPLAY 0.617021 (-6488 637);
PAINT ORANGE (-6488 637);
FORCEPROP 1 LAST PART_NUMBER G21497-005
J 2
(-6200 625);
DISPLAY 0.617021 (-6200 625);
PAINT BLUE (-6200 625);
FORCEPROP 1 LAST MATERIAL EMPTY
J 0
(-6425 575);
DISPLAY 0.617021 (-6425 575);
PAINT RED (-6425 575);
FORCEPROP 1 LAST PACK_TYPE 0402
J 0
(-6300 575);
DISPLAY 0.617021 (-6300 575);
PAINT SKYBLUE (-6300 575);
FORCEPROP 2 LAST CDS_LOCATION R1C9
J 2
(-6675 625);
DISPLAY 0.617021 (-6675 625);
PAINT AQUA (-6675 625);
DISPLAY INVISIBLE (-6675 625);
FORCEPROP 2 LAST CDS_LIB mstr_discrete
J 0
(-6550 625);
PAINT ORANGE (-6550 625);
DISPLAY INVISIBLE (-6550 625);
FORCEPROP 0 LAST ROOM IO_SLOT
J 0
(-6475 725);
DISPLAY 1.021277 (-6475 725);
PAINT ORANGE (-6475 725);
DISPLAY INVISIBLE (-6475 725);
FORCEPROP 1 LAST PATH I104
J 0
(-6600 775);
DISPLAY 0.978723 (-6600 775);
PAINT WHITE (-6600 775);
DISPLAY INVISIBLE (-6600 775);
FORCEPROP 2 LAST SEC_TYPE 0402
J 0
(-6600 825);
DISPLAY 1.021277 (-6600 825);
PAINT ORANGE (-6600 825);
DISPLAY INVISIBLE (-6600 825);
FORCEPROP 2 LAST SEC 1
J 0
(-6600 825);
DISPLAY 0.680851 (-6600 825);
PAINT MONO (-6600 825);
DISPLAY INVISIBLE (-6600 825);
FORCEPROP 2 LAST NO_XNET_CONNECTION 1
J 0
(-6600 825);
PAINT MONO (-6600 825);
DISPLAY INVISIBLE (-6600 825);
FORCEADD OFFPAGE..1
(-7425 625);
FORCEPROP 2 LAST $XR0 120 
J 0
(-7677 625);
DISPLAY 0.638298 (-7677 625);
PAINT MONO (-7677 625);
FORCEPROP 2 LAST $XR1 133 
J 0
(-7797 625);
DISPLAY 0.638298 (-7797 625);
PAINT MONO (-7797 625);
FORCEPROP 2 LAST $XR2 145 
J 0
(-7917 625);
DISPLAY 0.638298 (-7917 625);
PAINT MONO (-7917 625);
FORCEPROP 2 LAST $XR3 182 
J 0
(-7677 589);
DISPLAY 0.638298 (-7677 589);
PAINT MONO (-7677 589);
FORCEPROP 2 LAST CDS_LIB mstr_standard
J 0
(-7425 625);
PAINT ORANGE (-7425 625);
DISPLAY INVISIBLE (-7425 625);
FORCEPROP 2 LAST PATH I105
J 0
(-7375 700);
DISPLAY 1.021277 (-7375 700);
PAINT ORANGE (-7375 700);
DISPLAY INVISIBLE (-7375 700);
FORCEPROP 1 LAST COMMENT_BODY TRUE
J 0
(-7300 525);
DISPLAY 0.872340 (-7300 525);
PAINT GREEN (-7300 525);
DISPLAY INVISIBLE (-7300 525);
FORCEPROP 1 LAST OFFPAGE TRUE
J 0
(-7100 500);
DISPLAY 0.872340 (-7100 500);
PAINT GREEN (-7100 500);
DISPLAY INVISIBLE (-7100 500);
FORCEADD OFFPAGE..2
(-5525 500);
FORCEPROP 2 LAST $XR0 181 
J 0
(-5336 500);
DISPLAY 0.638298 (-5336 500);
PAINT MONO (-5336 500);
FORCEPROP 1 LAST COMMENT_BODY TRUE
J 0
(-5570 405);
DISPLAY 0.872340 (-5570 405);
PAINT GREEN (-5570 405);
DISPLAY INVISIBLE (-5570 405);
FORCEPROP 1 LAST OFFPAGE TRUE
J 0
(-5200 375);
DISPLAY 0.872340 (-5200 375);
PAINT GREEN (-5200 375);
DISPLAY INVISIBLE (-5200 375);
FORCEPROP 2 LAST CDS_LIB mstr_standard
J 0
(-5525 500);
PAINT ORANGE (-5525 500);
DISPLAY INVISIBLE (-5525 500);
FORCEPROP 2 LAST PATH I106
J 0
(-5325 575);
DISPLAY 1.021277 (-5325 575);
PAINT ORANGE (-5325 575);
DISPLAY INVISIBLE (-5325 575);
FORCEADD RES..1
(-6550 500);
FORCEPROP 1 LAST WATTAGE 1/16W
J 2
(-6675 450);
DISPLAY 0.617021 (-6675 450);
PAINT SKYBLUE (-6675 450);
FORCEPROP 1 LAST LOCATION R1F9
J 2
(-6675 500);
DISPLAY 0.617021 (-6675 500);
PAINT AQUA (-6675 500);
FORCEPROP 1 LAST VALUE 0.0
J 2
(-6575 450);
DISPLAY 0.617021 (-6575 450);
PAINT SKYBLUE (-6575 450);
FORCEPROP 1 LAST TOLERANCE 5%
J 0
(-6500 450);
DISPLAY 0.617021 (-6500 450);
PAINT SKYBLUE (-6500 450);
FORCEPROP 1 LAST MATERIAL EMPTY
J 0
(-6425 450);
DISPLAY 0.617021 (-6425 450);
PAINT RED (-6425 450);
FORCEPROP 1 LAST PACK_TYPE 0402
J 0
(-6300 450);
DISPLAY 0.617021 (-6300 450);
PAINT SKYBLUE (-6300 450);
FORCEPROP 1 LASTPIN (-6650 500) $PN 1
J 0
(-6638 512);
DISPLAY 0.617021 (-6638 512);
PAINT ORANGE (-6638 512);
FORCEPROP 1 LASTPIN (-6450 500) $PN 2
J 0
(-6488 512);
DISPLAY 0.617021 (-6488 512);
PAINT ORANGE (-6488 512);
FORCEPROP 1 LAST PART_NUMBER G21497-005
J 2
(-6200 500);
DISPLAY 0.617021 (-6200 500);
PAINT BLUE (-6200 500);
FORCEPROP 2 LAST CDS_LOCATION R1F9
J 2
(-6675 500);
DISPLAY 0.617021 (-6675 500);
PAINT AQUA (-6675 500);
DISPLAY INVISIBLE (-6675 500);
FORCEPROP 2 LAST CDS_LIB mstr_discrete
J 0
(-6550 500);
PAINT ORANGE (-6550 500);
DISPLAY INVISIBLE (-6550 500);
FORCEPROP 1 LAST PATH I107
J 0
(-6600 650);
DISPLAY 0.978723 (-6600 650);
PAINT WHITE (-6600 650);
DISPLAY INVISIBLE (-6600 650);
FORCEPROP 2 LAST SEC_TYPE 0402
J 0
(-6600 700);
DISPLAY 1.021277 (-6600 700);
PAINT ORANGE (-6600 700);
DISPLAY INVISIBLE (-6600 700);
FORCEPROP 2 LAST SEC 1
J 0
(-6600 700);
DISPLAY 0.680851 (-6600 700);
PAINT MONO (-6600 700);
DISPLAY INVISIBLE (-6600 700);
FORCEPROP 2 LAST NO_XNET_CONNECTION 1
J 0
(-6600 700);
PAINT MONO (-6600 700);
DISPLAY INVISIBLE (-6600 700);
FORCEPROP 0 LAST ROOM IO_SLOT
J 0
(-6475 600);
DISPLAY 1.021277 (-6475 600);
PAINT ORANGE (-6475 600);
DISPLAY INVISIBLE (-6475 600);
FORCEADD OFFPAGE..1
(-7425 500);
FORCEPROP 2 LAST $XR0 120 
J 0
(-7677 500);
DISPLAY 0.638298 (-7677 500);
PAINT MONO (-7677 500);
FORCEPROP 2 LAST $XR1 133 
J 0
(-7797 500);
DISPLAY 0.638298 (-7797 500);
PAINT MONO (-7797 500);
FORCEPROP 2 LAST $XR2 146 
J 0
(-7917 500);
DISPLAY 0.638298 (-7917 500);
PAINT MONO (-7917 500);
FORCEPROP 2 LAST $XR3 119 
J 0
(-7677 464);
DISPLAY 0.638298 (-7677 464);
PAINT MONO (-7677 464);
FORCEPROP 1 LAST COMMENT_BODY TRUE
J 0
(-7300 400);
DISPLAY 0.872340 (-7300 400);
PAINT GREEN (-7300 400);
DISPLAY INVISIBLE (-7300 400);
FORCEPROP 2 LAST CDS_LIB mstr_standard
J 0
(-7425 500);
PAINT ORANGE (-7425 500);
DISPLAY INVISIBLE (-7425 500);
FORCEPROP 2 LAST PATH I108
J 0
(-7375 575);
DISPLAY 1.021277 (-7375 575);
PAINT ORANGE (-7375 575);
DISPLAY INVISIBLE (-7375 575);
FORCEPROP 1 LAST OFFPAGE TRUE
J 0
(-7100 375);
DISPLAY 0.872340 (-7100 375);
PAINT GREEN (-7100 375);
DISPLAY INVISIBLE (-7100 375);
FORCEADD OFFPAGE..4
(-5525 350);
FORCEPROP 2 LAST $XR0 181 
J 0
(-5339 350);
DISPLAY 0.638298 (-5339 350);
PAINT MONO (-5339 350);
FORCEPROP 1 LAST COMMENT_BODY TRUE
J 0
(-5550 250);
DISPLAY 0.872340 (-5550 250);
PAINT GREEN (-5550 250);
DISPLAY INVISIBLE (-5550 250);
FORCEPROP 2 LAST CDS_LIB mstr_standard
J 0
(-5525 350);
PAINT ORANGE (-5525 350);
DISPLAY INVISIBLE (-5525 350);
FORCEPROP 2 LAST PATH I109
J 0
(-5325 400);
DISPLAY 1.021277 (-5325 400);
PAINT ORANGE (-5325 400);
DISPLAY INVISIBLE (-5325 400);
FORCEPROP 1 LAST OFFPAGE TRUE
J 0
(-5200 225);
DISPLAY 0.872340 (-5200 225);
PAINT GREEN (-5200 225);
DISPLAY INVISIBLE (-5200 225);
FORCEADD RES..1
(-6550 350);
FORCEPROP 1 LAST LOCATION R1C31
J 2
(-6675 350);
DISPLAY 0.617021 (-6675 350);
PAINT AQUA (-6675 350);
FORCEPROP 1 LAST WATTAGE 1/16W
J 2
(-6675 300);
DISPLAY 0.617021 (-6675 300);
PAINT SKYBLUE (-6675 300);
FORCEPROP 1 LAST VALUE 0.0
J 2
(-6575 300);
DISPLAY 0.617021 (-6575 300);
PAINT SKYBLUE (-6575 300);
FORCEPROP 1 LASTPIN (-6650 350) $PN 1
J 0
(-6638 362);
DISPLAY 0.617021 (-6638 362);
PAINT ORANGE (-6638 362);
FORCEPROP 1 LAST TOLERANCE 5%
J 0
(-6500 300);
DISPLAY 0.617021 (-6500 300);
PAINT SKYBLUE (-6500 300);
FORCEPROP 1 LASTPIN (-6450 350) $PN 2
J 0
(-6488 362);
DISPLAY 0.617021 (-6488 362);
PAINT ORANGE (-6488 362);
FORCEPROP 1 LAST PART_NUMBER G21497-005
J 2
(-6200 350);
DISPLAY 0.617021 (-6200 350);
PAINT BLUE (-6200 350);
FORCEPROP 1 LAST MATERIAL EMPTY
J 0
(-6425 300);
DISPLAY 0.617021 (-6425 300);
PAINT RED (-6425 300);
FORCEPROP 1 LAST PACK_TYPE 0402
J 0
(-6300 300);
DISPLAY 0.617021 (-6300 300);
PAINT SKYBLUE (-6300 300);
FORCEPROP 2 LAST CDS_LOCATION R1C31
J 2
(-6675 350);
DISPLAY 0.617021 (-6675 350);
PAINT AQUA (-6675 350);
DISPLAY INVISIBLE (-6675 350);
FORCEPROP 2 LAST CDS_LIB mstr_discrete
J 0
(-6550 350);
PAINT ORANGE (-6550 350);
DISPLAY INVISIBLE (-6550 350);
FORCEPROP 0 LAST ROOM IO_SLOT
J 0
(-6475 450);
DISPLAY 1.021277 (-6475 450);
PAINT ORANGE (-6475 450);
DISPLAY INVISIBLE (-6475 450);
FORCEPROP 1 LAST PATH I110
J 0
(-6600 500);
DISPLAY 0.978723 (-6600 500);
PAINT WHITE (-6600 500);
DISPLAY INVISIBLE (-6600 500);
FORCEPROP 2 LAST SEC_TYPE 0402
J 0
(-6600 550);
DISPLAY 1.021277 (-6600 550);
PAINT ORANGE (-6600 550);
DISPLAY INVISIBLE (-6600 550);
FORCEPROP 2 LAST SEC 1
J 0
(-6600 550);
DISPLAY 0.680851 (-6600 550);
PAINT MONO (-6600 550);
DISPLAY INVISIBLE (-6600 550);
FORCEPROP 2 LAST NO_XNET_CONNECTION 1
J 0
(-6600 550);
PAINT MONO (-6600 550);
DISPLAY INVISIBLE (-6600 550);
FORCEADD OFFPAGE..5
(-7425 350);
FORCEPROP 2 LAST $XR0 133 
J 0
(-7680 350);
DISPLAY 0.638298 (-7680 350);
PAINT MONO (-7680 350);
FORCEPROP 2 LAST $XR1 182 
J 0
(-7800 350);
DISPLAY 0.638298 (-7800 350);
PAINT MONO (-7800 350);
FORCEPROP 2 LAST $XR2 119 
J 0
(-7920 350);
DISPLAY 0.638298 (-7920 350);
PAINT MONO (-7920 350);
FORCEPROP 2 LAST $XR3 147 
J 0
(-7680 314);
DISPLAY 0.638298 (-7680 314);
PAINT MONO (-7680 314);
FORCEPROP 2 LAST PATH I111
J 0
(-7675 400);
DISPLAY 1.021277 (-7675 400);
PAINT ORANGE (-7675 400);
DISPLAY INVISIBLE (-7675 400);
FORCEPROP 2 LAST CDS_LIB mstr_standard
J 0
(-7425 350);
PAINT ORANGE (-7425 350);
DISPLAY INVISIBLE (-7425 350);
FORCEPROP 1 LAST COMMENT_BODY TRUE
J 0
(-7325 275);
DISPLAY 0.872340 (-7325 275);
PAINT GREEN (-7325 275);
DISPLAY INVISIBLE (-7325 275);
FORCEPROP 1 LAST OFFPAGE TRUE
J 0
(-7100 225);
DISPLAY 0.872340 (-7100 225);
PAINT GREEN (-7100 225);
DISPLAY INVISIBLE (-7100 225);
FORCEADD CAP..2
(-2950 1950);
FORCEPROP 1 LAST VALUE 0.22UF
J 2
(-3025 1900);
DISPLAY 0.617021 (-3025 1900);
PAINT SKYBLUE (-3025 1900);
FORCEPROP 1 LASTPIN (-3050 1950) $PN 1
J 0
(-3060 1965);
DISPLAY 0.617021 (-3060 1965);
PAINT ORANGE (-3060 1965);
FORCEPROP 1 LASTPIN (-2850 1950) $PN 2
J 0
(-2865 1965);
DISPLAY 0.617021 (-2865 1965);
PAINT ORANGE (-2865 1965);
FORCEPROP 1 LAST VOLTAGE 16V
J 0
(-2850 1925);
DISPLAY 0.617021 (-2850 1925);
PAINT SKYBLUE (-2850 1925);
FORCEPROP 1 LAST MATERIAL X7R
J 0
(-2725 1925);
DISPLAY 0.617021 (-2725 1925);
PAINT SKYBLUE (-2725 1925);
FORCEPROP 1 LAST TOLERANCE 10%
J 2
(-2525 1925);
DISPLAY 0.617021 (-2525 1925);
PAINT SKYBLUE (-2525 1925);
FORCEPROP 1 LAST PACK_TYPE 0402
J 1
(-2425 1925);
DISPLAY 0.617021 (-2425 1925);
PAINT SKYBLUE (-2425 1925);
FORCEPROP 1 LAST PART_NUMBER A36096-155
J 1
(-2725 2025);
DISPLAY 0.617021 (-2725 2025);
PAINT BLUE (-2725 2025);
FORCEPROP 1 LAST LOCATION C9N17
J 1
(-2950 2025);
DISPLAY 0.617021 (-2950 2025);
PAINT AQUA (-2950 2025);
FORCEPROP 2 LAST CDS_LIB mstr_discrete
J 0
(-2950 1950);
PAINT ORANGE (-2950 1950);
DISPLAY INVISIBLE (-2950 1950);
FORCEPROP 2 LAST CDS_LOCATION C9N17
J 1
(-2950 2025);
DISPLAY 0.617021 (-2950 2025);
PAINT AQUA (-2950 2025);
DISPLAY INVISIBLE (-2950 2025);
FORCEPROP 0 LAST BOM_COST IO_SLOT
J 0
(-2950 2100);
DISPLAY 1.021277 (-2950 2100);
PAINT ORANGE (-2950 2100);
DISPLAY INVISIBLE (-2950 2100);
FORCEPROP 2 LAST SEC_TYPE 0402
J 0
(-2950 2200);
DISPLAY 1.021277 (-2950 2200);
PAINT ORANGE (-2950 2200);
DISPLAY INVISIBLE (-2950 2200);
FORCEPROP 2 LAST SEC 1
J 0
(-2950 2200);
DISPLAY 0.680851 (-2950 2200);
PAINT MONO (-2950 2200);
DISPLAY INVISIBLE (-2950 2200);
FORCEPROP 1 LAST PATH I12
J 0
(-2950 2150);
DISPLAY 0.978723 (-2950 2150);
PAINT WHITE (-2950 2150);
DISPLAY INVISIBLE (-2950 2150);
FORCEPROP 0 LAST ROOM IO_SLOT
J 0
(-2950 2150);
DISPLAY 1.021277 (-2950 2150);
PAINT ORANGE (-2950 2150);
DISPLAY INVISIBLE (-2950 2150);
FORCEADD CAP..2
(-2475 1850);
FORCEPROP 1 LASTPIN (-2575 1850) $PN 1
J 0
(-2585 1865);
DISPLAY 0.617021 (-2585 1865);
PAINT ORANGE (-2585 1865);
FORCEPROP 1 LAST VALUE 0.22UF
J 2
(-2525 1825);
DISPLAY 0.617021 (-2525 1825);
PAINT SKYBLUE (-2525 1825);
FORCEPROP 1 LAST LOCATION C9N15
J 1
(-2475 1900);
DISPLAY 0.617021 (-2475 1900);
PAINT AQUA (-2475 1900);
FORCEPROP 1 LASTPIN (-2375 1850) $PN 2
J 0
(-2390 1865);
DISPLAY 0.617021 (-2390 1865);
PAINT ORANGE (-2390 1865);
FORCEPROP 1 LAST VOLTAGE 16V
J 0
(-2375 1825);
DISPLAY 0.617021 (-2375 1825);
PAINT SKYBLUE (-2375 1825);
FORCEPROP 1 LAST MATERIAL X7R
J 0
(-2250 1825);
DISPLAY 0.617021 (-2250 1825);
PAINT SKYBLUE (-2250 1825);
FORCEPROP 1 LAST TOLERANCE 10%
J 2
(-2050 1825);
DISPLAY 0.617021 (-2050 1825);
PAINT SKYBLUE (-2050 1825);
FORCEPROP 1 LAST PART_NUMBER A36096-155
J 1
(-2175 1875);
DISPLAY 0.617021 (-2175 1875);
PAINT BLUE (-2175 1875);
FORCEPROP 1 LAST PACK_TYPE 0402
J 1
(-1950 1825);
DISPLAY 0.617021 (-1950 1825);
PAINT SKYBLUE (-1950 1825);
FORCEPROP 2 LAST CDS_LIB mstr_discrete
J 0
(-2475 1850);
PAINT ORANGE (-2475 1850);
DISPLAY INVISIBLE (-2475 1850);
FORCEPROP 2 LAST CDS_LOCATION C9N15
J 1
(-2475 1900);
DISPLAY 0.617021 (-2475 1900);
PAINT AQUA (-2475 1900);
DISPLAY INVISIBLE (-2475 1900);
FORCEPROP 0 LAST BOM_COST IO_SLOT
J 0
(-2475 2000);
DISPLAY 1.021277 (-2475 2000);
PAINT ORANGE (-2475 2000);
DISPLAY INVISIBLE (-2475 2000);
FORCEPROP 0 LAST ROOM IO_SLOT
J 0
(-2475 2050);
DISPLAY 1.021277 (-2475 2050);
PAINT ORANGE (-2475 2050);
DISPLAY INVISIBLE (-2475 2050);
FORCEPROP 1 LAST PATH I13
J 0
(-2475 2050);
DISPLAY 0.978723 (-2475 2050);
PAINT WHITE (-2475 2050);
DISPLAY INVISIBLE (-2475 2050);
FORCEPROP 2 LAST SEC 1
J 0
(-2475 2100);
DISPLAY 0.680851 (-2475 2100);
PAINT MONO (-2475 2100);
DISPLAY INVISIBLE (-2475 2100);
FORCEPROP 2 LAST SEC_TYPE 0402
J 0
(-2475 2100);
DISPLAY 1.021277 (-2475 2100);
PAINT ORANGE (-2475 2100);
DISPLAY INVISIBLE (-2475 2100);
FORCEADD CAP..2
(-2475 1700);
FORCEPROP 1 LASTPIN (-2575 1700) $PN 1
J 0
(-2585 1715);
DISPLAY 0.617021 (-2585 1715);
PAINT ORANGE (-2585 1715);
FORCEPROP 1 LAST VALUE 0.22UF
J 2
(-2525 1675);
DISPLAY 0.617021 (-2525 1675);
PAINT SKYBLUE (-2525 1675);
FORCEPROP 1 LASTPIN (-2375 1700) $PN 2
J 0
(-2390 1715);
DISPLAY 0.617021 (-2390 1715);
PAINT ORANGE (-2390 1715);
FORCEPROP 1 LAST LOCATION C9N1
J 1
(-2450 1750);
DISPLAY 0.617021 (-2450 1750);
PAINT AQUA (-2450 1750);
FORCEPROP 1 LAST VOLTAGE 16V
J 0
(-2375 1675);
DISPLAY 0.617021 (-2375 1675);
PAINT SKYBLUE (-2375 1675);
FORCEPROP 1 LAST MATERIAL X7R
J 0
(-2250 1675);
DISPLAY 0.617021 (-2250 1675);
PAINT SKYBLUE (-2250 1675);
FORCEPROP 1 LAST TOLERANCE 10%
J 2
(-2050 1675);
DISPLAY 0.617021 (-2050 1675);
PAINT SKYBLUE (-2050 1675);
FORCEPROP 1 LAST PART_NUMBER A36096-155
J 1
(-2175 1725);
DISPLAY 0.617021 (-2175 1725);
PAINT BLUE (-2175 1725);
FORCEPROP 1 LAST PACK_TYPE 0402
J 1
(-1950 1675);
DISPLAY 0.617021 (-1950 1675);
PAINT SKYBLUE (-1950 1675);
FORCEPROP 2 LAST CDS_LOCATION C9N1
J 1
(-2450 1750);
DISPLAY 0.617021 (-2450 1750);
PAINT AQUA (-2450 1750);
DISPLAY INVISIBLE (-2450 1750);
FORCEPROP 2 LAST CDS_LIB mstr_discrete
J 0
(-2475 1700);
PAINT ORANGE (-2475 1700);
DISPLAY INVISIBLE (-2475 1700);
FORCEPROP 0 LAST BOM_COST IO_SLOT
J 0
(-2475 1850);
DISPLAY 1.021277 (-2475 1850);
PAINT ORANGE (-2475 1850);
DISPLAY INVISIBLE (-2475 1850);
FORCEPROP 0 LAST ROOM IO_SLOT
J 0
(-2475 1900);
DISPLAY 1.021277 (-2475 1900);
PAINT ORANGE (-2475 1900);
DISPLAY INVISIBLE (-2475 1900);
FORCEPROP 1 LAST PATH I14
J 0
(-2475 1900);
DISPLAY 0.978723 (-2475 1900);
PAINT WHITE (-2475 1900);
DISPLAY INVISIBLE (-2475 1900);
FORCEPROP 2 LAST SEC 1
J 0
(-2475 1950);
DISPLAY 0.680851 (-2475 1950);
PAINT MONO (-2475 1950);
DISPLAY INVISIBLE (-2475 1950);
FORCEPROP 2 LAST SEC_TYPE 0402
J 0
(-2475 1950);
DISPLAY 1.021277 (-2475 1950);
PAINT ORANGE (-2475 1950);
DISPLAY INVISIBLE (-2475 1950);
FORCEADD CAP..2
(-2950 1650);
FORCEPROP 1 LAST VALUE 0.22UF
J 2
(-3000 1600);
DISPLAY 0.617021 (-3000 1600);
PAINT SKYBLUE (-3000 1600);
FORCEPROP 1 LASTPIN (-3050 1650) $PN 1
J 0
(-3060 1665);
DISPLAY 0.617021 (-3060 1665);
PAINT ORANGE (-3060 1665);
FORCEPROP 1 LASTPIN (-2850 1650) $PN 2
J 0
(-2865 1665);
DISPLAY 0.617021 (-2865 1665);
PAINT ORANGE (-2865 1665);
FORCEPROP 1 LAST LOCATION C9N2
J 1
(-2950 1725);
DISPLAY 0.617021 (-2950 1725);
PAINT AQUA (-2950 1725);
FORCEPROP 1 LAST VOLTAGE 16V
J 0
(-2850 1625);
DISPLAY 0.617021 (-2850 1625);
PAINT SKYBLUE (-2850 1625);
FORCEPROP 1 LAST PART_NUMBER A36096-155
J 1
(-2725 1725);
DISPLAY 0.617021 (-2725 1725);
PAINT BLUE (-2725 1725);
FORCEPROP 1 LAST MATERIAL X7R
J 0
(-2725 1625);
DISPLAY 0.617021 (-2725 1625);
PAINT SKYBLUE (-2725 1625);
FORCEPROP 1 LAST TOLERANCE 10%
J 2
(-2525 1625);
DISPLAY 0.617021 (-2525 1625);
PAINT SKYBLUE (-2525 1625);
FORCEPROP 1 LAST PACK_TYPE 0402
J 1
(-2425 1625);
DISPLAY 0.617021 (-2425 1625);
PAINT SKYBLUE (-2425 1625);
FORCEPROP 2 LAST CDS_LOCATION C9N2
J 1
(-2950 1725);
DISPLAY 0.617021 (-2950 1725);
PAINT AQUA (-2950 1725);
DISPLAY INVISIBLE (-2950 1725);
FORCEPROP 2 LAST CDS_LIB mstr_discrete
J 0
(-2950 1650);
PAINT ORANGE (-2950 1650);
DISPLAY INVISIBLE (-2950 1650);
FORCEPROP 1 LAST PATH I15
J 0
(-2950 1850);
DISPLAY 0.978723 (-2950 1850);
PAINT WHITE (-2950 1850);
DISPLAY INVISIBLE (-2950 1850);
FORCEPROP 0 LAST ROOM IO_SLOT
J 0
(-2950 1850);
DISPLAY 1.021277 (-2950 1850);
PAINT ORANGE (-2950 1850);
DISPLAY INVISIBLE (-2950 1850);
FORCEPROP 0 LAST BOM_COST IO_SLOT
J 0
(-2950 1800);
DISPLAY 1.021277 (-2950 1800);
PAINT ORANGE (-2950 1800);
DISPLAY INVISIBLE (-2950 1800);
FORCEPROP 2 LAST SEC 1
J 0
(-2950 1900);
DISPLAY 0.680851 (-2950 1900);
PAINT MONO (-2950 1900);
DISPLAY INVISIBLE (-2950 1900);
FORCEPROP 2 LAST SEC_TYPE 0402
J 0
(-2950 1900);
DISPLAY 1.021277 (-2950 1900);
PAINT ORANGE (-2950 1900);
DISPLAY INVISIBLE (-2950 1900);
FORCEADD CAP..2
(-2950 1800);
FORCEPROP 1 LAST VALUE 0.22UF
J 2
(-3000 1750);
DISPLAY 0.617021 (-3000 1750);
PAINT SKYBLUE (-3000 1750);
FORCEPROP 1 LASTPIN (-3050 1800) $PN 1
J 0
(-3060 1815);
DISPLAY 0.617021 (-3060 1815);
PAINT ORANGE (-3060 1815);
FORCEPROP 1 LAST LOCATION C9N12
J 1
(-2950 1875);
DISPLAY 0.617021 (-2950 1875);
PAINT AQUA (-2950 1875);
FORCEPROP 1 LASTPIN (-2850 1800) $PN 2
J 0
(-2865 1815);
DISPLAY 0.617021 (-2865 1815);
PAINT ORANGE (-2865 1815);
FORCEPROP 1 LAST VOLTAGE 16V
J 0
(-2850 1775);
DISPLAY 0.617021 (-2850 1775);
PAINT SKYBLUE (-2850 1775);
FORCEPROP 1 LAST PART_NUMBER A36096-155
J 1
(-2725 1875);
DISPLAY 0.617021 (-2725 1875);
PAINT BLUE (-2725 1875);
FORCEPROP 1 LAST MATERIAL X7R
J 0
(-2725 1775);
DISPLAY 0.617021 (-2725 1775);
PAINT SKYBLUE (-2725 1775);
FORCEPROP 1 LAST TOLERANCE 10%
J 2
(-2525 1775);
DISPLAY 0.617021 (-2525 1775);
PAINT SKYBLUE (-2525 1775);
FORCEPROP 1 LAST PACK_TYPE 0402
J 1
(-2425 1775);
DISPLAY 0.617021 (-2425 1775);
PAINT SKYBLUE (-2425 1775);
FORCEPROP 2 LAST CDS_LIB mstr_discrete
J 0
(-2950 1800);
PAINT ORANGE (-2950 1800);
DISPLAY INVISIBLE (-2950 1800);
FORCEPROP 2 LAST CDS_LOCATION C9N12
J 1
(-2950 1875);
DISPLAY 0.617021 (-2950 1875);
PAINT AQUA (-2950 1875);
DISPLAY INVISIBLE (-2950 1875);
FORCEPROP 0 LAST ROOM IO_SLOT
J 0
(-2950 2000);
DISPLAY 1.021277 (-2950 2000);
PAINT ORANGE (-2950 2000);
DISPLAY INVISIBLE (-2950 2000);
FORCEPROP 1 LAST PATH I16
J 0
(-2950 2000);
DISPLAY 0.978723 (-2950 2000);
PAINT WHITE (-2950 2000);
DISPLAY INVISIBLE (-2950 2000);
FORCEPROP 0 LAST BOM_COST IO_SLOT
J 0
(-2950 1950);
DISPLAY 1.021277 (-2950 1950);
PAINT ORANGE (-2950 1950);
DISPLAY INVISIBLE (-2950 1950);
FORCEPROP 2 LAST SEC_TYPE 0402
J 0
(-2950 2050);
DISPLAY 1.021277 (-2950 2050);
PAINT ORANGE (-2950 2050);
DISPLAY INVISIBLE (-2950 2050);
FORCEPROP 2 LAST SEC 1
J 0
(-2950 2050);
DISPLAY 0.680851 (-2950 2050);
PAINT MONO (-2950 2050);
DISPLAY INVISIBLE (-2950 2050);
FORCEADD GND..1
(-3750 1225);
FORCEPROP 3 LASTPIN (-3750 1275) SIG_NAME GND\g
J 0
(-3740 1285);
DISPLAY 0.659574 (-3740 1285);
PAINT MONO (-3740 1285);
DISPLAY INVISIBLE (-3740 1285);
FORCEPROP 1 LAST HDL_POWER GND
J 0
(-3750 1375);
DISPLAY 0.872340 (-3750 1375);
PAINT GREEN (-3750 1375);
DISPLAY INVISIBLE (-3750 1375);
FORCEPROP 2 LAST ROOM P2V5_LAN_AUX_VR
J 0
(-4050 1300);
DISPLAY 0.617021 (-4050 1300);
PAINT ORANGE (-4050 1300);
DISPLAY INVISIBLE (-4050 1300);
FORCEPROP 1 LAST PATH I17
J 0
(-3675 1225);
DISPLAY 0.872340 (-3675 1225);
PAINT AQUA (-3675 1225);
DISPLAY INVISIBLE (-3675 1225);
FORCEPROP 1 LAST BODY_TYPE PLUMBING
J 0
(-3795 1182);
DISPLAY 0.340426 (-3795 1182);
PAINT GREEN (-3795 1182);
DISPLAY INVISIBLE (-3795 1182);
FORCEPROP 1 LAST SIZE 1B
J 0
(-3675 1175);
DISPLAY 0.872340 (-3675 1175);
PAINT GREEN (-3675 1175);
DISPLAY INVISIBLE (-3675 1175);
FORCEPROP 2 LAST CDS_LIB mstr_symbols
J 0
(-3750 1225);
PAINT MONO (-3750 1225);
DISPLAY INVISIBLE (-3750 1225);
FORCEPROP 2 LAST BOM_COST NT_BASE_VRD
J 0
(-4050 1300);
DISPLAY 0.617021 (-4050 1300);
PAINT ORANGE (-4050 1300);
DISPLAY INVISIBLE (-4050 1300);
FORCEPROP 1 LAST VOLTAGE 0
J 0
(-3750 1225);
PAINT SKYBLUE (-3750 1225);
DISPLAY INVISIBLE (-3750 1225);
FORCEADD CONN76_H22707001..1
(-4425 2650);
FORCEPROP 2 LASTPIN (-4925 1750) $PN G4
J 2
(-4935 1760);
DISPLAY 0.617021 (-4935 1760);
PAINT ORANGE (-4935 1760);
FORCEPROP 2 LASTPIN (-4925 1600) $PN J4
J 2
(-4935 1610);
DISPLAY 0.617021 (-4935 1610);
PAINT ORANGE (-4935 1610);
FORCEPROP 2 LASTPIN (-4925 1700) $PN H4
J 2
(-4935 1710);
DISPLAY 0.617021 (-4935 1710);
PAINT ORANGE (-4935 1710);
FORCEPROP 2 LASTPIN (-4925 1650) $PN I4
J 2
(-4935 1660);
DISPLAY 0.617021 (-4935 1660);
PAINT ORANGE (-4935 1660);
FORCEPROP 2 LASTPIN (-4925 1800) $PN F4
J 2
(-4935 1810);
DISPLAY 0.617021 (-4935 1810);
PAINT ORANGE (-4935 1810);
FORCEPROP 2 LASTPIN (-4925 1850) $PN E4
J 2
(-4935 1860);
DISPLAY 0.617021 (-4935 1860);
PAINT ORANGE (-4935 1860);
FORCEPROP 2 LASTPIN (-4925 1950) $PN C4
J 2
(-4935 1960);
DISPLAY 0.617021 (-4935 1960);
PAINT ORANGE (-4935 1960);
FORCEPROP 2 LASTPIN (-4925 2000) $PN B4
J 2
(-4935 2010);
DISPLAY 0.617021 (-4935 2010);
PAINT ORANGE (-4935 2010);
FORCEPROP 2 LASTPIN (-4925 1900) $PN D4
J 2
(-4935 1910);
DISPLAY 0.617021 (-4935 1910);
PAINT ORANGE (-4935 1910);
FORCEPROP 1 LAST PART_NUMBER H22707-001
J 0
(-4875 1450);
DISPLAY 0.617021 (-4875 1450);
PAINT BLUE (-4875 1450);
FORCEPROP 2 LASTPIN (-4925 2200) $PN H3
J 2
(-4935 2210);
DISPLAY 0.617021 (-4935 2210);
PAINT ORANGE (-4935 2210);
FORCEPROP 2 LASTPIN (-4925 2250) $PN G3
J 2
(-4935 2260);
DISPLAY 0.617021 (-4935 2260);
PAINT ORANGE (-4935 2260);
FORCEPROP 2 LASTPIN (-4925 2150) $PN I3
J 2
(-4935 2160);
DISPLAY 0.617021 (-4935 2160);
PAINT ORANGE (-4935 2160);
FORCEPROP 2 LASTPIN (-4925 2050) $PN A4
J 2
(-4935 2060);
DISPLAY 0.617021 (-4935 2060);
PAINT ORANGE (-4935 2060);
FORCEPROP 2 LASTPIN (-4925 2350) $PN E3
J 2
(-4935 2360);
DISPLAY 0.617021 (-4935 2360);
PAINT ORANGE (-4935 2360);
FORCEPROP 2 LASTPIN (-4925 2400) $PN D3
J 2
(-4935 2410);
DISPLAY 0.617021 (-4935 2410);
PAINT ORANGE (-4935 2410);
FORCEPROP 2 LASTPIN (-4925 2500) $PN B3
J 2
(-4935 2510);
DISPLAY 0.617021 (-4935 2510);
PAINT ORANGE (-4935 2510);
FORCEPROP 2 LASTPIN (-4925 2300) $PN F3
J 2
(-4935 2310);
DISPLAY 0.617021 (-4935 2310);
PAINT ORANGE (-4935 2310);
FORCEPROP 2 LASTPIN (-4925 2450) $PN C3
J 2
(-4935 2460);
DISPLAY 0.617021 (-4935 2460);
PAINT ORANGE (-4935 2460);
FORCEPROP 2 LASTPIN (-4925 2550) $PN A3
J 2
(-4935 2560);
DISPLAY 0.617021 (-4935 2560);
PAINT ORANGE (-4935 2560);
FORCEPROP 2 LASTPIN (-4925 2650) $PN J2
J 2
(-4935 2660);
DISPLAY 0.617021 (-4935 2660);
PAINT ORANGE (-4935 2660);
FORCEPROP 2 LASTPIN (-4925 2750) $PN H2
J 2
(-4935 2760);
DISPLAY 0.617021 (-4935 2760);
PAINT ORANGE (-4935 2760);
FORCEPROP 2 LASTPIN (-4925 2700) $PN I2
J 2
(-4935 2710);
DISPLAY 0.617021 (-4935 2710);
PAINT ORANGE (-4935 2710);
FORCEPROP 2 LASTPIN (-4925 2800) $PN G2
J 2
(-4935 2810);
DISPLAY 0.617021 (-4935 2810);
PAINT ORANGE (-4935 2810);
FORCEPROP 2 LASTPIN (-4925 2850) $PN F2
J 2
(-4935 2860);
DISPLAY 0.617021 (-4935 2860);
PAINT ORANGE (-4935 2860);
FORCEPROP 2 LASTPIN (-4925 2900) $PN E2
J 2
(-4935 2910);
DISPLAY 0.617021 (-4935 2910);
PAINT ORANGE (-4935 2910);
FORCEPROP 2 LASTPIN (-4925 3000) $PN C2
J 2
(-4935 3010);
DISPLAY 0.617021 (-4935 3010);
PAINT ORANGE (-4935 3010);
FORCEPROP 2 LASTPIN (-4925 2950) $PN D2
J 2
(-4935 2960);
DISPLAY 0.617021 (-4935 2960);
PAINT ORANGE (-4935 2960);
FORCEPROP 2 LASTPIN (-4925 3050) $PN B2
J 2
(-4935 3060);
DISPLAY 0.617021 (-4935 3060);
PAINT ORANGE (-4935 3060);
FORCEPROP 2 LASTPIN (-4925 3100) $PN A2
J 2
(-4935 3110);
DISPLAY 0.617021 (-4935 3110);
PAINT ORANGE (-4935 3110);
FORCEPROP 2 LASTPIN (-4925 3200) $PN I1
J 2
(-4935 3210);
DISPLAY 0.617021 (-4935 3210);
PAINT ORANGE (-4935 3210);
FORCEPROP 2 LASTPIN (-4925 3250) $PN H1
J 2
(-4935 3260);
DISPLAY 0.617021 (-4935 3260);
PAINT ORANGE (-4935 3260);
FORCEPROP 2 LASTPIN (-4925 3300) $PN G1
J 2
(-4935 3310);
DISPLAY 0.617021 (-4935 3310);
PAINT ORANGE (-4935 3310);
FORCEPROP 2 LASTPIN (-4925 3400) $PN E1
J 2
(-4935 3410);
DISPLAY 0.617021 (-4935 3410);
PAINT ORANGE (-4935 3410);
FORCEPROP 2 LASTPIN (-4925 3450) $PN D1
J 2
(-4935 3460);
DISPLAY 0.617021 (-4935 3460);
PAINT ORANGE (-4935 3460);
FORCEPROP 2 LASTPIN (-4925 3350) $PN F1
J 2
(-4935 3360);
DISPLAY 0.617021 (-4935 3360);
PAINT ORANGE (-4935 3360);
FORCEPROP 2 LASTPIN (-4925 3500) $PN C1
J 2
(-4935 3510);
DISPLAY 0.617021 (-4935 3510);
PAINT ORANGE (-4935 3510);
FORCEPROP 2 LASTPIN (-4925 3550) $PN B1
J 2
(-4935 3560);
DISPLAY 0.617021 (-4935 3560);
PAINT ORANGE (-4935 3560);
FORCEPROP 2 LASTPIN (-4925 3600) $PN A1
J 2
(-4935 3610);
DISPLAY 0.617021 (-4935 3610);
PAINT ORANGE (-4935 3610);
FORCEPROP 1 LAST MATERIAL CONN
J 0
(-4875 3850);
DISPLAY 0.617021 (-4875 3850);
PAINT SKYBLUE (-4875 3850);
FORCEPROP 1 LAST LOCATION J1C1
J 0
(-4875 3900);
DISPLAY 0.617021 (-4875 3900);
PAINT AQUA (-4875 3900);
FORCEPROP 2 LASTPIN (-3925 1650) $PN I8
J 0
(-3915 1660);
DISPLAY 0.617021 (-3915 1660);
PAINT ORANGE (-3915 1660);
FORCEPROP 2 LASTPIN (-3925 1700) $PN H8
J 0
(-3915 1710);
DISPLAY 0.617021 (-3915 1710);
PAINT ORANGE (-3915 1710);
FORCEPROP 2 LASTPIN (-3925 1600) $PN J8
J 0
(-3915 1610);
DISPLAY 0.617021 (-3915 1610);
PAINT ORANGE (-3915 1610);
FORCEPROP 2 LASTPIN (-3925 1750) $PN G8
J 0
(-3915 1760);
DISPLAY 0.617021 (-3915 1760);
PAINT ORANGE (-3915 1760);
FORCEPROP 2 LASTPIN (-3925 1900) $PN D8
J 0
(-3915 1910);
DISPLAY 0.617021 (-3915 1910);
PAINT ORANGE (-3915 1910);
FORCEPROP 2 LASTPIN (-3925 2000) $PN B8
J 0
(-3915 2010);
DISPLAY 0.617021 (-3915 2010);
PAINT ORANGE (-3915 2010);
FORCEPROP 2 LASTPIN (-3925 1800) $PN F8
J 0
(-3915 1810);
DISPLAY 0.617021 (-3915 1810);
PAINT ORANGE (-3915 1810);
FORCEPROP 2 LASTPIN (-3925 1850) $PN E8
J 0
(-3915 1860);
DISPLAY 0.617021 (-3915 1860);
PAINT ORANGE (-3915 1860);
FORCEPROP 2 LASTPIN (-3925 1950) $PN C8
J 0
(-3915 1960);
DISPLAY 0.617021 (-3915 1960);
PAINT ORANGE (-3915 1960);
FORCEPROP 2 LASTPIN (-3925 2200) $PN H7
J 0
(-3915 2210);
DISPLAY 0.617021 (-3915 2210);
PAINT ORANGE (-3915 2210);
FORCEPROP 2 LASTPIN (-3925 2250) $PN G7
J 0
(-3915 2260);
DISPLAY 0.617021 (-3915 2260);
PAINT ORANGE (-3915 2260);
FORCEPROP 2 LASTPIN (-3925 2150) $PN I7
J 0
(-3915 2160);
DISPLAY 0.617021 (-3915 2160);
PAINT ORANGE (-3915 2160);
FORCEPROP 2 LASTPIN (-3925 2050) $PN A8
J 0
(-3915 2060);
DISPLAY 0.617021 (-3915 2060);
PAINT ORANGE (-3915 2060);
FORCEPROP 2 LASTPIN (-3925 2450) $PN C7
J 0
(-3915 2460);
DISPLAY 0.617021 (-3915 2460);
PAINT ORANGE (-3915 2460);
FORCEPROP 2 LASTPIN (-3925 2350) $PN E7
J 0
(-3915 2360);
DISPLAY 0.617021 (-3915 2360);
PAINT ORANGE (-3915 2360);
FORCEPROP 2 LASTPIN (-3925 2400) $PN D7
J 0
(-3915 2410);
DISPLAY 0.617021 (-3915 2410);
PAINT ORANGE (-3915 2410);
FORCEPROP 2 LASTPIN (-3925 2500) $PN B7
J 0
(-3915 2510);
DISPLAY 0.617021 (-3915 2510);
PAINT ORANGE (-3915 2510);
FORCEPROP 2 LASTPIN (-3925 2300) $PN F7
J 0
(-3915 2310);
DISPLAY 0.617021 (-3915 2310);
PAINT ORANGE (-3915 2310);
FORCEPROP 2 LASTPIN (-3925 2550) $PN A7
J 0
(-3915 2560);
DISPLAY 0.617021 (-3915 2560);
PAINT ORANGE (-3915 2560);
FORCEPROP 2 LASTPIN (-3925 2700) $PN I6
J 0
(-3915 2710);
DISPLAY 0.617021 (-3915 2710);
PAINT ORANGE (-3915 2710);
FORCEPROP 2 LASTPIN (-3925 2750) $PN H6
J 0
(-3915 2760);
DISPLAY 0.617021 (-3915 2760);
PAINT ORANGE (-3915 2760);
FORCEPROP 2 LASTPIN (-3925 2650) $PN J6
J 0
(-3915 2660);
DISPLAY 0.617021 (-3915 2660);
PAINT ORANGE (-3915 2660);
FORCEPROP 2 LASTPIN (-3925 2800) $PN G6
J 0
(-3915 2810);
DISPLAY 0.617021 (-3915 2810);
PAINT ORANGE (-3915 2810);
FORCEPROP 2 LASTPIN (-3925 2850) $PN F6
J 0
(-3915 2860);
DISPLAY 0.617021 (-3915 2860);
PAINT ORANGE (-3915 2860);
FORCEPROP 2 LASTPIN (-3925 2900) $PN E6
J 0
(-3915 2910);
DISPLAY 0.617021 (-3915 2910);
PAINT ORANGE (-3915 2910);
FORCEPROP 2 LASTPIN (-3925 3000) $PN C6
J 0
(-3915 3010);
DISPLAY 0.617021 (-3915 3010);
PAINT ORANGE (-3915 3010);
FORCEPROP 2 LASTPIN (-3925 2950) $PN D6
J 0
(-3915 2960);
DISPLAY 0.617021 (-3915 2960);
PAINT ORANGE (-3915 2960);
FORCEPROP 2 LASTPIN (-3925 3050) $PN B6
J 0
(-3915 3060);
DISPLAY 0.617021 (-3915 3060);
PAINT ORANGE (-3915 3060);
FORCEPROP 2 LASTPIN (-3925 3100) $PN A6
J 0
(-3915 3110);
DISPLAY 0.617021 (-3915 3110);
PAINT ORANGE (-3915 3110);
FORCEPROP 2 LASTPIN (-3925 3200) $PN I5
J 0
(-3915 3210);
DISPLAY 0.617021 (-3915 3210);
PAINT ORANGE (-3915 3210);
FORCEPROP 2 LASTPIN (-3925 3250) $PN H5
J 0
(-3915 3260);
DISPLAY 0.617021 (-3915 3260);
PAINT ORANGE (-3915 3260);
FORCEPROP 2 LASTPIN (-3925 3300) $PN G5
J 0
(-3915 3310);
DISPLAY 0.617021 (-3915 3310);
PAINT ORANGE (-3915 3310);
FORCEPROP 2 LASTPIN (-3925 3400) $PN E5
J 0
(-3915 3410);
DISPLAY 0.617021 (-3915 3410);
PAINT ORANGE (-3915 3410);
FORCEPROP 2 LASTPIN (-3925 3450) $PN D5
J 0
(-3915 3460);
DISPLAY 0.617021 (-3915 3460);
PAINT ORANGE (-3915 3460);
FORCEPROP 2 LASTPIN (-3925 3350) $PN F5
J 0
(-3915 3360);
DISPLAY 0.617021 (-3915 3360);
PAINT ORANGE (-3915 3360);
FORCEPROP 2 LASTPIN (-3925 3500) $PN C5
J 0
(-3915 3510);
DISPLAY 0.617021 (-3915 3510);
PAINT ORANGE (-3915 3510);
FORCEPROP 2 LASTPIN (-3925 3550) $PN B5
J 0
(-3915 3560);
DISPLAY 0.617021 (-3915 3560);
PAINT ORANGE (-3915 3560);
FORCEPROP 2 LASTPIN (-3925 3600) $PN A5
J 0
(-3915 3610);
DISPLAY 0.617021 (-3915 3610);
PAINT ORANGE (-3915 3610);
FORCEPROP 2 LAST CDS_LIB mstr_conn
J 0
(-4425 2650);
PAINT ORANGE (-4425 2650);
DISPLAY INVISIBLE (-4425 2650);
FORCEPROP 0 LAST ROOM IO_SLOT
J 0
(-4875 4000);
DISPLAY 1.021277 (-4875 4000);
PAINT ORANGE (-4875 4000);
DISPLAY INVISIBLE (-4875 4000);
FORCEPROP 2 LAST CDS_LOCATION J1C1
J 0
(-4875 3900);
DISPLAY 0.617021 (-4875 3900);
PAINT AQUA (-4875 3900);
DISPLAY INVISIBLE (-4875 3900);
FORCEPROP 2 LAST SEC 1
J 0
(-4875 3950);
DISPLAY 0.680851 (-4875 3950);
PAINT MONO (-4875 3950);
DISPLAY INVISIBLE (-4875 3950);
FORCEPROP 2 LAST SEC_TYPE THMT1
J 0
(-4875 3950);
DISPLAY 1.021277 (-4875 3950);
PAINT ORANGE (-4875 3950);
DISPLAY INVISIBLE (-4875 3950);
FORCEPROP 1 LAST PACK_TYPE THMT1
J 0
(-4875 3950);
PAINT SKYBLUE (-4875 3950);
DISPLAY INVISIBLE (-4875 3950);
FORCEPROP 1 LAST PATH I18
J 0
(-4350 3850);
PAINT GREEN (-4350 3850);
DISPLAY INVISIBLE (-4350 3850);
FORCEPROP 0 LAST BOM_COST IO_SLOT
J 0
(-4875 4100);
DISPLAY 1.021277 (-4875 4100);
PAINT ORANGE (-4875 4100);
DISPLAY INVISIBLE (-4875 4100);
FORCEADD GND..1
(-5150 1275);
FORCEPROP 3 LASTPIN (-5150 1325) SIG_NAME GND\g
J 0
(-5140 1335);
DISPLAY 0.659574 (-5140 1335);
PAINT MONO (-5140 1335);
DISPLAY INVISIBLE (-5140 1335);
FORCEPROP 1 LAST VOLTAGE 0
J 0
(-5150 1275);
PAINT SKYBLUE (-5150 1275);
DISPLAY INVISIBLE (-5150 1275);
FORCEPROP 2 LAST BOM_COST NT_BASE_VRD
J 0
(-5450 1350);
DISPLAY 0.617021 (-5450 1350);
PAINT ORANGE (-5450 1350);
DISPLAY INVISIBLE (-5450 1350);
FORCEPROP 1 LAST HDL_POWER GND
J 0
(-5150 1425);
DISPLAY 0.872340 (-5150 1425);
PAINT GREEN (-5150 1425);
DISPLAY INVISIBLE (-5150 1425);
FORCEPROP 2 LAST ROOM P2V5_LAN_AUX_VR
J 0
(-5450 1350);
DISPLAY 0.617021 (-5450 1350);
PAINT ORANGE (-5450 1350);
DISPLAY INVISIBLE (-5450 1350);
FORCEPROP 1 LAST BODY_TYPE PLUMBING
J 0
(-5195 1232);
DISPLAY 0.340426 (-5195 1232);
PAINT GREEN (-5195 1232);
DISPLAY INVISIBLE (-5195 1232);
FORCEPROP 2 LAST CDS_LIB mstr_symbols
J 0
(-5150 1275);
PAINT ORANGE (-5150 1275);
DISPLAY INVISIBLE (-5150 1275);
FORCEPROP 1 LAST PATH I19
J 0
(-5075 1275);
DISPLAY 0.872340 (-5075 1275);
PAINT AQUA (-5075 1275);
DISPLAY INVISIBLE (-5075 1275);
FORCEPROP 1 LAST SIZE 1B
J 0
(-5075 1225);
DISPLAY 0.872340 (-5075 1225);
PAINT GREEN (-5075 1225);
DISPLAY INVISIBLE (-5075 1225);
FORCEADD TAP..6
R 2
(-1475 2000);
FORCEPROP 3 LASTPIN (-1525 2000) SIG_NAME P3E_CPU1_PE3_MP_TXN<8>
J 0
(-1515 2010);
DISPLAY 0.659574 (-1515 2010);
PAINT MONO (-1515 2010);
DISPLAY INVISIBLE (-1515 2010);
FORCEPROP 1 LASTPIN (-1525 2000) BN 8
J 2
(-1473 2008);
DISPLAY 0.617021 (-1473 2008);
PAINT GREEN (-1473 2008);
FORCEPROP 1 LAST HDL_TAP TRUE
J 2
(-1800 1875);
DISPLAY 1.234043 (-1800 1875);
PAINT GREEN (-1800 1875);
DISPLAY INVISIBLE (-1800 1875);
FORCEPROP 1 LAST PATH I2
J 2
(-1473 2000);
DISPLAY 0.872340 (-1473 2000);
PAINT GREEN (-1473 2000);
DISPLAY INVISIBLE (-1473 2000);
FORCEPROP 1 LAST BODY_TYPE PLUMBING
J 2
(-1475 1950);
DISPLAY 1.234043 (-1475 1950);
PAINT GREEN (-1475 1950);
DISPLAY INVISIBLE (-1475 1950);
FORCEPROP 2 LAST CDS_LIB mstr_standard
J 0
(-1475 2000);
PAINT ORANGE (-1475 2000);
DISPLAY INVISIBLE (-1475 2000);
FORCEADD OFFPAGE..1
R 2
(-600 3675);
FORCEPROP 2 LAST $XR0 66 
J 0
(-414 3675);
DISPLAY 0.638298 (-414 3675);
PAINT MONO (-414 3675);
FORCEPROP 1 LAST COMMENT_BODY TRUE
J 2
(-725 3575);
DISPLAY 0.872340 (-725 3575);
PAINT GREEN (-725 3575);
DISPLAY INVISIBLE (-725 3575);
FORCEPROP 1 LAST OFFPAGE TRUE
J 2
(-925 3550);
DISPLAY 0.872340 (-925 3550);
PAINT GREEN (-925 3550);
DISPLAY INVISIBLE (-925 3550);
FORCEPROP 2 LAST CDS_LIB mstr_standard
J 0
(-600 3675);
PAINT ORANGE (-600 3675);
DISPLAY INVISIBLE (-600 3675);
FORCEPROP 2 LAST PATH I29
J 0
(-400 3725);
DISPLAY 1.021277 (-400 3725);
PAINT ORANGE (-400 3725);
DISPLAY INVISIBLE (-400 3725);
FORCEADD OFFPAGE..1
R 2
(-600 3575);
FORCEPROP 2 LAST $XR0 66 
J 0
(-414 3575);
DISPLAY 0.638298 (-414 3575);
PAINT MONO (-414 3575);
FORCEPROP 1 LAST COMMENT_BODY TRUE
J 2
(-725 3475);
DISPLAY 0.872340 (-725 3475);
PAINT GREEN (-725 3475);
DISPLAY INVISIBLE (-725 3475);
FORCEPROP 1 LAST OFFPAGE TRUE
J 2
(-925 3450);
DISPLAY 0.872340 (-925 3450);
PAINT GREEN (-925 3450);
DISPLAY INVISIBLE (-925 3450);
FORCEPROP 2 LAST CDS_LIB mstr_standard
J 0
(-600 3575);
PAINT ORANGE (-600 3575);
DISPLAY INVISIBLE (-600 3575);
FORCEPROP 2 LAST PATH I30
J 0
(-400 3625);
DISPLAY 1.021277 (-400 3625);
PAINT ORANGE (-400 3625);
DISPLAY INVISIBLE (-400 3625);
FORCEADD TAP..6
R 2
(-1725 1950);
FORCEPROP 3 LASTPIN (-1775 1950) SIG_NAME P3E_CPU1_PE3_MP_TXP<8>
J 0
(-1765 1960);
DISPLAY 0.659574 (-1765 1960);
PAINT MONO (-1765 1960);
DISPLAY INVISIBLE (-1765 1960);
FORCEPROP 1 LASTPIN (-1775 1950) BN 8
J 2
(-1723 1958);
DISPLAY 0.617021 (-1723 1958);
PAINT GREEN (-1723 1958);
FORCEPROP 1 LAST HDL_TAP TRUE
J 2
(-2050 1825);
DISPLAY 1.234043 (-2050 1825);
PAINT GREEN (-2050 1825);
DISPLAY INVISIBLE (-2050 1825);
FORCEPROP 1 LAST BODY_TYPE PLUMBING
J 2
(-1725 1900);
DISPLAY 1.234043 (-1725 1900);
PAINT GREEN (-1725 1900);
DISPLAY INVISIBLE (-1725 1900);
FORCEPROP 1 LAST PATH I4
J 2
(-1723 1950);
DISPLAY 0.872340 (-1723 1950);
PAINT GREEN (-1723 1950);
DISPLAY INVISIBLE (-1723 1950);
FORCEPROP 2 LAST CDS_LIB mstr_standard
J 0
(-1725 1950);
PAINT ORANGE (-1725 1950);
DISPLAY INVISIBLE (-1725 1950);
FORCEADD TAP..6
R 2
(-1475 2900);
FORCEPROP 3 LASTPIN (-1525 2900) SIG_NAME P3E_CPU1_PE3_MP_TXN<14>
J 0
(-1515 2910);
DISPLAY 0.659574 (-1515 2910);
PAINT MONO (-1515 2910);
DISPLAY INVISIBLE (-1515 2910);
FORCEPROP 1 LASTPIN (-1525 2900) BN 14
J 2
(-1473 2908);
DISPLAY 0.617021 (-1473 2908);
PAINT GREEN (-1473 2908);
FORCEPROP 1 LAST HDL_TAP TRUE
J 2
(-1800 2775);
DISPLAY 1.234043 (-1800 2775);
PAINT GREEN (-1800 2775);
DISPLAY INVISIBLE (-1800 2775);
FORCEPROP 1 LAST PATH I41
J 2
(-1473 2900);
DISPLAY 0.872340 (-1473 2900);
PAINT GREEN (-1473 2900);
DISPLAY INVISIBLE (-1473 2900);
FORCEPROP 1 LAST BODY_TYPE PLUMBING
J 2
(-1475 2850);
DISPLAY 1.234043 (-1475 2850);
PAINT GREEN (-1475 2850);
DISPLAY INVISIBLE (-1475 2850);
FORCEPROP 2 LAST CDS_LIB mstr_standard
J 0
(-1475 2900);
PAINT ORANGE (-1475 2900);
DISPLAY INVISIBLE (-1475 2900);
FORCEADD TAP..6
R 2
(-1475 2750);
FORCEPROP 3 LASTPIN (-1525 2750) SIG_NAME P3E_CPU1_PE3_MP_TXN<15>
J 0
(-1515 2760);
DISPLAY 0.659574 (-1515 2760);
PAINT MONO (-1515 2760);
DISPLAY INVISIBLE (-1515 2760);
FORCEPROP 1 LASTPIN (-1525 2750) BN 15
J 2
(-1473 2758);
DISPLAY 0.617021 (-1473 2758);
PAINT GREEN (-1473 2758);
FORCEPROP 1 LAST HDL_TAP TRUE
J 2
(-1800 2625);
DISPLAY 1.234043 (-1800 2625);
PAINT GREEN (-1800 2625);
DISPLAY INVISIBLE (-1800 2625);
FORCEPROP 1 LAST PATH I42
J 2
(-1473 2750);
DISPLAY 0.872340 (-1473 2750);
PAINT GREEN (-1473 2750);
DISPLAY INVISIBLE (-1473 2750);
FORCEPROP 1 LAST BODY_TYPE PLUMBING
J 2
(-1475 2700);
DISPLAY 1.234043 (-1475 2700);
PAINT GREEN (-1475 2700);
DISPLAY INVISIBLE (-1475 2700);
FORCEPROP 2 LAST CDS_LIB mstr_standard
J 0
(-1475 2750);
PAINT ORANGE (-1475 2750);
DISPLAY INVISIBLE (-1475 2750);
FORCEADD TAP..6
R 2
(-1475 2550);
FORCEPROP 3 LASTPIN (-1525 2550) SIG_NAME P3E_CPU1_PE3_MP_TXN<11>
J 0
(-1515 2560);
DISPLAY 0.659574 (-1515 2560);
PAINT MONO (-1515 2560);
DISPLAY INVISIBLE (-1515 2560);
FORCEPROP 1 LASTPIN (-1525 2550) BN 11
J 2
(-1473 2558);
DISPLAY 0.617021 (-1473 2558);
PAINT GREEN (-1473 2558);
FORCEPROP 1 LAST HDL_TAP TRUE
J 2
(-1800 2425);
DISPLAY 1.234043 (-1800 2425);
PAINT GREEN (-1800 2425);
DISPLAY INVISIBLE (-1800 2425);
FORCEPROP 1 LAST BODY_TYPE PLUMBING
J 2
(-1475 2500);
DISPLAY 1.234043 (-1475 2500);
PAINT GREEN (-1475 2500);
DISPLAY INVISIBLE (-1475 2500);
FORCEPROP 1 LAST PATH I43
J 2
(-1473 2550);
DISPLAY 0.872340 (-1473 2550);
PAINT GREEN (-1473 2550);
DISPLAY INVISIBLE (-1473 2550);
FORCEPROP 2 LAST CDS_LIB mstr_standard
J 0
(-1475 2550);
PAINT ORANGE (-1475 2550);
DISPLAY INVISIBLE (-1475 2550);
FORCEADD TAP..6
R 2
(-1725 2850);
FORCEPROP 3 LASTPIN (-1775 2850) SIG_NAME P3E_CPU1_PE3_MP_TXP<14>
J 0
(-1765 2860);
DISPLAY 0.659574 (-1765 2860);
PAINT MONO (-1765 2860);
DISPLAY INVISIBLE (-1765 2860);
FORCEPROP 1 LASTPIN (-1775 2850) BN 14
J 2
(-1723 2858);
DISPLAY 0.617021 (-1723 2858);
PAINT GREEN (-1723 2858);
FORCEPROP 1 LAST HDL_TAP TRUE
J 2
(-2050 2725);
DISPLAY 1.234043 (-2050 2725);
PAINT GREEN (-2050 2725);
DISPLAY INVISIBLE (-2050 2725);
FORCEPROP 1 LAST BODY_TYPE PLUMBING
J 2
(-1725 2800);
DISPLAY 1.234043 (-1725 2800);
PAINT GREEN (-1725 2800);
DISPLAY INVISIBLE (-1725 2800);
FORCEPROP 1 LAST PATH I44
J 2
(-1723 2850);
DISPLAY 0.872340 (-1723 2850);
PAINT GREEN (-1723 2850);
DISPLAY INVISIBLE (-1723 2850);
FORCEPROP 2 LAST CDS_LIB mstr_standard
J 0
(-1725 2850);
PAINT ORANGE (-1725 2850);
DISPLAY INVISIBLE (-1725 2850);
FORCEADD TAP..6
R 2
(-1725 2700);
FORCEPROP 3 LASTPIN (-1775 2700) SIG_NAME P3E_CPU1_PE3_MP_TXP<15>
J 0
(-1765 2710);
DISPLAY 0.659574 (-1765 2710);
PAINT MONO (-1765 2710);
DISPLAY INVISIBLE (-1765 2710);
FORCEPROP 1 LASTPIN (-1775 2700) BN 15
J 2
(-1723 2708);
DISPLAY 0.617021 (-1723 2708);
PAINT GREEN (-1723 2708);
FORCEPROP 1 LAST HDL_TAP TRUE
J 2
(-2050 2575);
DISPLAY 1.234043 (-2050 2575);
PAINT GREEN (-2050 2575);
DISPLAY INVISIBLE (-2050 2575);
FORCEPROP 1 LAST PATH I45
J 2
(-1723 2700);
DISPLAY 0.872340 (-1723 2700);
PAINT GREEN (-1723 2700);
DISPLAY INVISIBLE (-1723 2700);
FORCEPROP 1 LAST BODY_TYPE PLUMBING
J 2
(-1725 2650);
DISPLAY 1.234043 (-1725 2650);
PAINT GREEN (-1725 2650);
DISPLAY INVISIBLE (-1725 2650);
FORCEPROP 2 LAST CDS_LIB mstr_standard
J 0
(-1725 2700);
PAINT ORANGE (-1725 2700);
DISPLAY INVISIBLE (-1725 2700);
FORCEADD TAP..6
R 2
(-1725 2500);
FORCEPROP 3 LASTPIN (-1775 2500) SIG_NAME P3E_CPU1_PE3_MP_TXP<11>
J 0
(-1765 2510);
DISPLAY 0.659574 (-1765 2510);
PAINT MONO (-1765 2510);
DISPLAY INVISIBLE (-1765 2510);
FORCEPROP 1 LASTPIN (-1775 2500) BN 11
J 2
(-1723 2508);
DISPLAY 0.617021 (-1723 2508);
PAINT GREEN (-1723 2508);
FORCEPROP 1 LAST HDL_TAP TRUE
J 2
(-2050 2375);
DISPLAY 1.234043 (-2050 2375);
PAINT GREEN (-2050 2375);
DISPLAY INVISIBLE (-2050 2375);
FORCEPROP 1 LAST PATH I46
J 2
(-1723 2500);
DISPLAY 0.872340 (-1723 2500);
PAINT GREEN (-1723 2500);
DISPLAY INVISIBLE (-1723 2500);
FORCEPROP 1 LAST BODY_TYPE PLUMBING
J 2
(-1725 2450);
DISPLAY 1.234043 (-1725 2450);
PAINT GREEN (-1725 2450);
DISPLAY INVISIBLE (-1725 2450);
FORCEPROP 2 LAST CDS_LIB mstr_standard
J 0
(-1725 2500);
PAINT ORANGE (-1725 2500);
DISPLAY INVISIBLE (-1725 2500);
FORCEADD TAP..6
R 2
(-1475 2400);
FORCEPROP 3 LASTPIN (-1525 2400) SIG_NAME P3E_CPU1_PE3_MP_TXN<12>
J 0
(-1515 2410);
DISPLAY 0.659574 (-1515 2410);
PAINT MONO (-1515 2410);
DISPLAY INVISIBLE (-1515 2410);
FORCEPROP 1 LASTPIN (-1525 2400) BN 12
J 2
(-1473 2408);
DISPLAY 0.617021 (-1473 2408);
PAINT GREEN (-1473 2408);
FORCEPROP 1 LAST HDL_TAP TRUE
J 2
(-1800 2275);
DISPLAY 1.234043 (-1800 2275);
PAINT GREEN (-1800 2275);
DISPLAY INVISIBLE (-1800 2275);
FORCEPROP 1 LAST BODY_TYPE PLUMBING
J 2
(-1475 2350);
DISPLAY 1.234043 (-1475 2350);
PAINT GREEN (-1475 2350);
DISPLAY INVISIBLE (-1475 2350);
FORCEPROP 1 LAST PATH I47
J 2
(-1473 2400);
DISPLAY 0.872340 (-1473 2400);
PAINT GREEN (-1473 2400);
DISPLAY INVISIBLE (-1473 2400);
FORCEPROP 2 LAST CDS_LIB mstr_standard
J 0
(-1475 2400);
PAINT ORANGE (-1475 2400);
DISPLAY INVISIBLE (-1475 2400);
FORCEADD TAP..6
R 2
(-1725 2350);
FORCEPROP 3 LASTPIN (-1775 2350) SIG_NAME P3E_CPU1_PE3_MP_TXP<12>
J 0
(-1765 2360);
DISPLAY 0.659574 (-1765 2360);
PAINT MONO (-1765 2360);
DISPLAY INVISIBLE (-1765 2360);
FORCEPROP 1 LASTPIN (-1775 2350) BN 12
J 2
(-1723 2358);
DISPLAY 0.617021 (-1723 2358);
PAINT GREEN (-1723 2358);
FORCEPROP 1 LAST HDL_TAP TRUE
J 2
(-2050 2225);
DISPLAY 1.234043 (-2050 2225);
PAINT GREEN (-2050 2225);
DISPLAY INVISIBLE (-2050 2225);
FORCEPROP 1 LAST BODY_TYPE PLUMBING
J 2
(-1725 2300);
DISPLAY 1.234043 (-1725 2300);
PAINT GREEN (-1725 2300);
DISPLAY INVISIBLE (-1725 2300);
FORCEPROP 1 LAST PATH I48
J 2
(-1723 2350);
DISPLAY 0.872340 (-1723 2350);
PAINT GREEN (-1723 2350);
DISPLAY INVISIBLE (-1723 2350);
FORCEPROP 2 LAST CDS_LIB mstr_standard
J 0
(-1725 2350);
PAINT ORANGE (-1725 2350);
DISPLAY INVISIBLE (-1725 2350);
FORCEADD CAP..2
(-2475 2750);
FORCEPROP 1 LASTPIN (-2575 2750) $PN 1
J 0
(-2585 2765);
DISPLAY 0.617021 (-2585 2765);
PAINT ORANGE (-2585 2765);
FORCEPROP 1 LAST VALUE 0.22UF
J 2
(-2525 2725);
DISPLAY 0.617021 (-2525 2725);
PAINT SKYBLUE (-2525 2725);
FORCEPROP 1 LASTPIN (-2375 2750) $PN 2
J 0
(-2390 2765);
DISPLAY 0.617021 (-2390 2765);
PAINT ORANGE (-2390 2765);
FORCEPROP 1 LAST LOCATION C9N9
J 1
(-2475 2850);
DISPLAY 0.617021 (-2475 2850);
PAINT AQUA (-2475 2850);
FORCEPROP 1 LAST VOLTAGE 16V
J 0
(-2375 2725);
DISPLAY 0.617021 (-2375 2725);
PAINT SKYBLUE (-2375 2725);
FORCEPROP 1 LAST PART_NUMBER A36096-155
J 1
(-2200 2775);
DISPLAY 0.617021 (-2200 2775);
PAINT BLUE (-2200 2775);
FORCEPROP 1 LAST MATERIAL X7R
J 0
(-2250 2725);
DISPLAY 0.617021 (-2250 2725);
PAINT SKYBLUE (-2250 2725);
FORCEPROP 1 LAST TOLERANCE 10%
J 2
(-2050 2725);
DISPLAY 0.617021 (-2050 2725);
PAINT SKYBLUE (-2050 2725);
FORCEPROP 1 LAST PACK_TYPE 0402
J 1
(-1950 2725);
DISPLAY 0.617021 (-1950 2725);
PAINT SKYBLUE (-1950 2725);
FORCEPROP 2 LAST CDS_LIB mstr_discrete
J 0
(-2475 2750);
PAINT ORANGE (-2475 2750);
DISPLAY INVISIBLE (-2475 2750);
FORCEPROP 0 LAST BOM_COST IO_SLOT
J 0
(-2475 2900);
DISPLAY 1.021277 (-2475 2900);
PAINT ORANGE (-2475 2900);
DISPLAY INVISIBLE (-2475 2900);
FORCEPROP 2 LAST SEC_TYPE 0402
J 0
(-2475 3000);
DISPLAY 1.021277 (-2475 3000);
PAINT ORANGE (-2475 3000);
DISPLAY INVISIBLE (-2475 3000);
FORCEPROP 2 LAST SEC 1
J 0
(-2475 3000);
DISPLAY 0.680851 (-2475 3000);
PAINT MONO (-2475 3000);
DISPLAY INVISIBLE (-2475 3000);
FORCEPROP 2 LAST CDS_LOCATION C9N9
J 1
(-2475 2850);
DISPLAY 0.617021 (-2475 2850);
PAINT AQUA (-2475 2850);
DISPLAY INVISIBLE (-2475 2850);
FORCEPROP 1 LAST PATH I49
J 0
(-2475 2950);
DISPLAY 0.978723 (-2475 2950);
PAINT WHITE (-2475 2950);
DISPLAY INVISIBLE (-2475 2950);
FORCEPROP 0 LAST ROOM IO_SLOT
J 0
(-2475 2950);
DISPLAY 1.021277 (-2475 2950);
PAINT ORANGE (-2475 2950);
DISPLAY INVISIBLE (-2475 2950);
FORCEADD TAP..6
R 2
(-1475 1850);
FORCEPROP 3 LASTPIN (-1525 1850) SIG_NAME P3E_CPU1_PE3_MP_TXN<9>
J 0
(-1515 1860);
DISPLAY 0.659574 (-1515 1860);
PAINT MONO (-1515 1860);
DISPLAY INVISIBLE (-1515 1860);
FORCEPROP 1 LASTPIN (-1525 1850) BN 9
J 2
(-1473 1858);
DISPLAY 0.617021 (-1473 1858);
PAINT GREEN (-1473 1858);
FORCEPROP 1 LAST HDL_TAP TRUE
J 2
(-1800 1725);
DISPLAY 1.234043 (-1800 1725);
PAINT GREEN (-1800 1725);
DISPLAY INVISIBLE (-1800 1725);
FORCEPROP 1 LAST PATH I5
J 2
(-1473 1850);
DISPLAY 0.872340 (-1473 1850);
PAINT GREEN (-1473 1850);
DISPLAY INVISIBLE (-1473 1850);
FORCEPROP 1 LAST BODY_TYPE PLUMBING
J 2
(-1475 1800);
DISPLAY 1.234043 (-1475 1800);
PAINT GREEN (-1475 1800);
DISPLAY INVISIBLE (-1475 1800);
FORCEPROP 2 LAST CDS_LIB mstr_standard
J 0
(-1475 1850);
PAINT ORANGE (-1475 1850);
DISPLAY INVISIBLE (-1475 1850);
FORCEADD CAP..2
(-2475 2900);
FORCEPROP 1 LASTPIN (-2575 2900) $PN 1
J 0
(-2585 2915);
DISPLAY 0.617021 (-2585 2915);
PAINT ORANGE (-2585 2915);
FORCEPROP 1 LAST VALUE 0.22UF
J 2
(-2525 2875);
DISPLAY 0.617021 (-2525 2875);
PAINT SKYBLUE (-2525 2875);
FORCEPROP 1 LAST LOCATION C9N8
J 1
(-2475 2950);
DISPLAY 0.617021 (-2475 2950);
PAINT AQUA (-2475 2950);
FORCEPROP 1 LASTPIN (-2375 2900) $PN 2
J 0
(-2390 2915);
DISPLAY 0.617021 (-2390 2915);
PAINT ORANGE (-2390 2915);
FORCEPROP 1 LAST VOLTAGE 16V
J 0
(-2375 2875);
DISPLAY 0.617021 (-2375 2875);
PAINT SKYBLUE (-2375 2875);
FORCEPROP 1 LAST PART_NUMBER A36096-155
J 1
(-2200 2925);
DISPLAY 0.617021 (-2200 2925);
PAINT BLUE (-2200 2925);
FORCEPROP 1 LAST MATERIAL X7R
J 0
(-2250 2875);
DISPLAY 0.617021 (-2250 2875);
PAINT SKYBLUE (-2250 2875);
FORCEPROP 1 LAST TOLERANCE 10%
J 2
(-2050 2875);
DISPLAY 0.617021 (-2050 2875);
PAINT SKYBLUE (-2050 2875);
FORCEPROP 1 LAST PACK_TYPE 0402
J 1
(-1950 2875);
DISPLAY 0.617021 (-1950 2875);
PAINT SKYBLUE (-1950 2875);
FORCEPROP 2 LAST CDS_LIB mstr_discrete
J 0
(-2475 2900);
PAINT ORANGE (-2475 2900);
DISPLAY INVISIBLE (-2475 2900);
FORCEPROP 2 LAST CDS_LOCATION C9N8
J 1
(-2475 2950);
DISPLAY 0.617021 (-2475 2950);
PAINT AQUA (-2475 2950);
DISPLAY INVISIBLE (-2475 2950);
FORCEPROP 0 LAST BOM_COST IO_SLOT
J 0
(-2475 3050);
DISPLAY 1.021277 (-2475 3050);
PAINT ORANGE (-2475 3050);
DISPLAY INVISIBLE (-2475 3050);
FORCEPROP 0 LAST ROOM IO_SLOT
J 0
(-2475 3100);
DISPLAY 1.021277 (-2475 3100);
PAINT ORANGE (-2475 3100);
DISPLAY INVISIBLE (-2475 3100);
FORCEPROP 1 LAST PATH I50
J 0
(-2475 3100);
DISPLAY 0.978723 (-2475 3100);
PAINT WHITE (-2475 3100);
DISPLAY INVISIBLE (-2475 3100);
FORCEPROP 2 LAST SEC 1
J 0
(-2475 3150);
DISPLAY 0.680851 (-2475 3150);
PAINT MONO (-2475 3150);
DISPLAY INVISIBLE (-2475 3150);
FORCEPROP 2 LAST SEC_TYPE 0402
J 0
(-2475 3150);
DISPLAY 1.021277 (-2475 3150);
PAINT ORANGE (-2475 3150);
DISPLAY INVISIBLE (-2475 3150);
FORCEADD CAP..2
(-2475 2550);
FORCEPROP 1 LASTPIN (-2575 2550) $PN 1
J 0
(-2585 2565);
DISPLAY 0.617021 (-2585 2565);
PAINT ORANGE (-2585 2565);
FORCEPROP 1 LAST VALUE 0.22UF
J 2
(-2525 2525);
DISPLAY 0.617021 (-2525 2525);
PAINT SKYBLUE (-2525 2525);
FORCEPROP 1 LAST VOLTAGE 16V
J 0
(-2375 2525);
DISPLAY 0.617021 (-2375 2525);
PAINT SKYBLUE (-2375 2525);
FORCEPROP 1 LAST MATERIAL X7R
J 0
(-2250 2525);
DISPLAY 0.617021 (-2250 2525);
PAINT SKYBLUE (-2250 2525);
FORCEPROP 1 LAST TOLERANCE 10%
J 2
(-2050 2525);
DISPLAY 0.617021 (-2050 2525);
PAINT SKYBLUE (-2050 2525);
FORCEPROP 1 LAST LOCATION C9N3
J 1
(-2475 2650);
DISPLAY 0.617021 (-2475 2650);
PAINT AQUA (-2475 2650);
FORCEPROP 1 LASTPIN (-2375 2550) $PN 2
J 0
(-2390 2565);
DISPLAY 0.617021 (-2390 2565);
PAINT ORANGE (-2390 2565);
FORCEPROP 1 LAST PART_NUMBER A36096-155
J 1
(-2200 2575);
DISPLAY 0.617021 (-2200 2575);
PAINT BLUE (-2200 2575);
FORCEPROP 1 LAST PACK_TYPE 0402
J 1
(-1950 2525);
DISPLAY 0.617021 (-1950 2525);
PAINT SKYBLUE (-1950 2525);
FORCEPROP 2 LAST CDS_LIB mstr_discrete
J 0
(-2475 2550);
PAINT ORANGE (-2475 2550);
DISPLAY INVISIBLE (-2475 2550);
FORCEPROP 0 LAST BOM_COST IO_SLOT
J 0
(-2475 2700);
DISPLAY 1.021277 (-2475 2700);
PAINT ORANGE (-2475 2700);
DISPLAY INVISIBLE (-2475 2700);
FORCEPROP 2 LAST CDS_LOCATION C9N3
J 1
(-2475 2650);
DISPLAY 0.617021 (-2475 2650);
PAINT AQUA (-2475 2650);
DISPLAY INVISIBLE (-2475 2650);
FORCEPROP 1 LAST PATH I51
J 0
(-2475 2750);
DISPLAY 0.978723 (-2475 2750);
PAINT WHITE (-2475 2750);
DISPLAY INVISIBLE (-2475 2750);
FORCEPROP 0 LAST ROOM IO_SLOT
J 0
(-2475 2750);
DISPLAY 1.021277 (-2475 2750);
PAINT ORANGE (-2475 2750);
DISPLAY INVISIBLE (-2475 2750);
FORCEPROP 2 LAST SEC 1
J 0
(-2475 2800);
DISPLAY 0.680851 (-2475 2800);
PAINT MONO (-2475 2800);
DISPLAY INVISIBLE (-2475 2800);
FORCEPROP 2 LAST SEC_TYPE 0402
J 0
(-2475 2800);
DISPLAY 1.021277 (-2475 2800);
PAINT ORANGE (-2475 2800);
DISPLAY INVISIBLE (-2475 2800);
FORCEADD CAP..2
(-2475 2400);
FORCEPROP 1 LASTPIN (-2575 2400) $PN 1
J 0
(-2585 2415);
DISPLAY 0.617021 (-2585 2415);
PAINT ORANGE (-2585 2415);
FORCEPROP 1 LAST VALUE 0.22UF
J 2
(-2525 2375);
DISPLAY 0.617021 (-2525 2375);
PAINT SKYBLUE (-2525 2375);
FORCEPROP 1 LAST LOCATION C9N16
J 1
(-2475 2500);
DISPLAY 0.617021 (-2475 2500);
PAINT AQUA (-2475 2500);
FORCEPROP 1 LASTPIN (-2375 2400) $PN 2
J 0
(-2390 2415);
DISPLAY 0.617021 (-2390 2415);
PAINT ORANGE (-2390 2415);
FORCEPROP 1 LAST VOLTAGE 16V
J 0
(-2375 2375);
DISPLAY 0.617021 (-2375 2375);
PAINT SKYBLUE (-2375 2375);
FORCEPROP 1 LAST PART_NUMBER A36096-155
J 1
(-2200 2425);
DISPLAY 0.617021 (-2200 2425);
PAINT BLUE (-2200 2425);
FORCEPROP 1 LAST MATERIAL X7R
J 0
(-2250 2375);
DISPLAY 0.617021 (-2250 2375);
PAINT SKYBLUE (-2250 2375);
FORCEPROP 1 LAST TOLERANCE 10%
J 2
(-2050 2375);
DISPLAY 0.617021 (-2050 2375);
PAINT SKYBLUE (-2050 2375);
FORCEPROP 1 LAST PACK_TYPE 0402
J 1
(-1950 2375);
DISPLAY 0.617021 (-1950 2375);
PAINT SKYBLUE (-1950 2375);
FORCEPROP 2 LAST CDS_LIB mstr_discrete
J 0
(-2475 2400);
PAINT ORANGE (-2475 2400);
DISPLAY INVISIBLE (-2475 2400);
FORCEPROP 2 LAST CDS_LOCATION C9N16
J 1
(-2475 2500);
DISPLAY 0.617021 (-2475 2500);
PAINT AQUA (-2475 2500);
DISPLAY INVISIBLE (-2475 2500);
FORCEPROP 0 LAST BOM_COST IO_SLOT
J 0
(-2475 2550);
DISPLAY 1.021277 (-2475 2550);
PAINT ORANGE (-2475 2550);
DISPLAY INVISIBLE (-2475 2550);
FORCEPROP 2 LAST SEC_TYPE 0402
J 0
(-2475 2650);
DISPLAY 1.021277 (-2475 2650);
PAINT ORANGE (-2475 2650);
DISPLAY INVISIBLE (-2475 2650);
FORCEPROP 2 LAST SEC 1
J 0
(-2475 2650);
DISPLAY 0.680851 (-2475 2650);
PAINT MONO (-2475 2650);
DISPLAY INVISIBLE (-2475 2650);
FORCEPROP 1 LAST PATH I52
J 0
(-2475 2600);
DISPLAY 0.978723 (-2475 2600);
PAINT WHITE (-2475 2600);
DISPLAY INVISIBLE (-2475 2600);
FORCEPROP 0 LAST ROOM IO_SLOT
J 0
(-2475 2600);
DISPLAY 1.021277 (-2475 2600);
PAINT ORANGE (-2475 2600);
DISPLAY INVISIBLE (-2475 2600);
FORCEADD CAP..2
(-2950 2850);
FORCEPROP 1 LAST PART_NUMBER A36096-155
J 1
(-3325 2800);
DISPLAY 0.617021 (-3325 2800);
PAINT BLUE (-3325 2800);
FORCEPROP 1 LAST VALUE 0.22UF
J 2
(-3025 2800);
DISPLAY 0.617021 (-3025 2800);
PAINT SKYBLUE (-3025 2800);
FORCEPROP 1 LASTPIN (-3050 2850) $PN 1
J 0
(-3060 2865);
DISPLAY 0.617021 (-3060 2865);
PAINT ORANGE (-3060 2865);
FORCEPROP 1 LAST LOCATION C9N10
J 1
(-2950 2950);
DISPLAY 0.617021 (-2950 2950);
PAINT AQUA (-2950 2950);
FORCEPROP 1 LASTPIN (-2850 2850) $PN 2
J 0
(-2865 2865);
DISPLAY 0.617021 (-2865 2865);
PAINT ORANGE (-2865 2865);
FORCEPROP 1 LAST VOLTAGE 16V
J 0
(-2850 2825);
DISPLAY 0.617021 (-2850 2825);
PAINT SKYBLUE (-2850 2825);
FORCEPROP 1 LAST MATERIAL X7R
J 0
(-2725 2825);
DISPLAY 0.617021 (-2725 2825);
PAINT SKYBLUE (-2725 2825);
FORCEPROP 1 LAST TOLERANCE 10%
J 2
(-2525 2825);
DISPLAY 0.617021 (-2525 2825);
PAINT SKYBLUE (-2525 2825);
FORCEPROP 1 LAST PACK_TYPE 0402
J 1
(-2425 2825);
DISPLAY 0.617021 (-2425 2825);
PAINT SKYBLUE (-2425 2825);
FORCEPROP 2 LAST CDS_LOCATION C9N10
J 1
(-2950 2950);
DISPLAY 0.617021 (-2950 2950);
PAINT AQUA (-2950 2950);
DISPLAY INVISIBLE (-2950 2950);
FORCEPROP 2 LAST CDS_LIB mstr_discrete
J 0
(-2950 2850);
PAINT ORANGE (-2950 2850);
DISPLAY INVISIBLE (-2950 2850);
FORCEPROP 0 LAST BOM_COST IO_SLOT
J 0
(-2950 3000);
DISPLAY 1.021277 (-2950 3000);
PAINT ORANGE (-2950 3000);
DISPLAY INVISIBLE (-2950 3000);
FORCEPROP 0 LAST ROOM IO_SLOT
J 0
(-2950 3050);
DISPLAY 1.021277 (-2950 3050);
PAINT ORANGE (-2950 3050);
DISPLAY INVISIBLE (-2950 3050);
FORCEPROP 1 LAST PATH I53
J 0
(-2950 3050);
DISPLAY 0.978723 (-2950 3050);
PAINT WHITE (-2950 3050);
DISPLAY INVISIBLE (-2950 3050);
FORCEPROP 2 LAST SEC 1
J 0
(-2950 3100);
DISPLAY 0.680851 (-2950 3100);
PAINT MONO (-2950 3100);
DISPLAY INVISIBLE (-2950 3100);
FORCEPROP 2 LAST SEC_TYPE 0402
J 0
(-2950 3100);
DISPLAY 1.021277 (-2950 3100);
PAINT ORANGE (-2950 3100);
DISPLAY INVISIBLE (-2950 3100);
FORCEADD CAP..2
(-2950 2700);
FORCEPROP 1 LAST VALUE 0.22UF
J 2
(-3025 2650);
DISPLAY 0.617021 (-3025 2650);
PAINT SKYBLUE (-3025 2650);
FORCEPROP 1 LASTPIN (-3050 2700) $PN 1
J 0
(-3060 2715);
DISPLAY 0.617021 (-3060 2715);
PAINT ORANGE (-3060 2715);
FORCEPROP 1 LAST LOCATION C9N7
J 1
(-2950 2775);
DISPLAY 0.617021 (-2950 2775);
PAINT AQUA (-2950 2775);
FORCEPROP 1 LASTPIN (-2850 2700) $PN 2
J 0
(-2865 2715);
DISPLAY 0.617021 (-2865 2715);
PAINT ORANGE (-2865 2715);
FORCEPROP 1 LAST VOLTAGE 16V
J 0
(-2850 2675);
DISPLAY 0.617021 (-2850 2675);
PAINT SKYBLUE (-2850 2675);
FORCEPROP 1 LAST PART_NUMBER A36096-155
J 1
(-2800 2750);
DISPLAY 0.617021 (-2800 2750);
PAINT BLUE (-2800 2750);
FORCEPROP 1 LAST MATERIAL X7R
J 0
(-2725 2675);
DISPLAY 0.617021 (-2725 2675);
PAINT SKYBLUE (-2725 2675);
FORCEPROP 1 LAST TOLERANCE 10%
J 2
(-2525 2675);
DISPLAY 0.617021 (-2525 2675);
PAINT SKYBLUE (-2525 2675);
FORCEPROP 1 LAST PACK_TYPE 0402
J 1
(-2425 2675);
DISPLAY 0.617021 (-2425 2675);
PAINT SKYBLUE (-2425 2675);
FORCEPROP 2 LAST CDS_LOCATION C9N7
J 1
(-2950 2775);
DISPLAY 0.617021 (-2950 2775);
PAINT AQUA (-2950 2775);
DISPLAY INVISIBLE (-2950 2775);
FORCEPROP 2 LAST CDS_LIB mstr_discrete
J 0
(-2950 2700);
PAINT ORANGE (-2950 2700);
DISPLAY INVISIBLE (-2950 2700);
FORCEPROP 2 LAST SEC_TYPE 0402
J 0
(-2950 2950);
DISPLAY 1.021277 (-2950 2950);
PAINT ORANGE (-2950 2950);
DISPLAY INVISIBLE (-2950 2950);
FORCEPROP 0 LAST BOM_COST IO_SLOT
J 0
(-2950 2850);
DISPLAY 1.021277 (-2950 2850);
PAINT ORANGE (-2950 2850);
DISPLAY INVISIBLE (-2950 2850);
FORCEPROP 2 LAST SEC 1
J 0
(-2950 2950);
DISPLAY 0.680851 (-2950 2950);
PAINT MONO (-2950 2950);
DISPLAY INVISIBLE (-2950 2950);
FORCEPROP 1 LAST PATH I54
J 0
(-2950 2900);
DISPLAY 0.978723 (-2950 2900);
PAINT WHITE (-2950 2900);
DISPLAY INVISIBLE (-2950 2900);
FORCEPROP 0 LAST ROOM IO_SLOT
J 0
(-2950 2900);
DISPLAY 1.021277 (-2950 2900);
PAINT ORANGE (-2950 2900);
DISPLAY INVISIBLE (-2950 2900);
FORCEADD CAP..2
(-2950 2500);
FORCEPROP 1 LAST VALUE 0.22UF
J 2
(-3025 2450);
DISPLAY 0.617021 (-3025 2450);
PAINT SKYBLUE (-3025 2450);
FORCEPROP 1 LASTPIN (-3050 2500) $PN 1
J 0
(-3060 2515);
DISPLAY 0.617021 (-3060 2515);
PAINT ORANGE (-3060 2515);
FORCEPROP 1 LASTPIN (-2850 2500) $PN 2
J 0
(-2865 2515);
DISPLAY 0.617021 (-2865 2515);
PAINT ORANGE (-2865 2515);
FORCEPROP 1 LAST VOLTAGE 16V
J 0
(-2850 2475);
DISPLAY 0.617021 (-2850 2475);
PAINT SKYBLUE (-2850 2475);
FORCEPROP 1 LAST MATERIAL X7R
J 0
(-2725 2475);
DISPLAY 0.617021 (-2725 2475);
PAINT SKYBLUE (-2725 2475);
FORCEPROP 1 LAST LOCATION C9N4
J 1
(-2950 2575);
DISPLAY 0.617021 (-2950 2575);
PAINT AQUA (-2950 2575);
FORCEPROP 1 LAST PART_NUMBER A36096-155
J 1
(-2750 2575);
DISPLAY 0.617021 (-2750 2575);
PAINT BLUE (-2750 2575);
FORCEPROP 1 LAST TOLERANCE 10%
J 2
(-2525 2475);
DISPLAY 0.617021 (-2525 2475);
PAINT SKYBLUE (-2525 2475);
FORCEPROP 1 LAST PACK_TYPE 0402
J 1
(-2425 2475);
DISPLAY 0.617021 (-2425 2475);
PAINT SKYBLUE (-2425 2475);
FORCEPROP 2 LAST CDS_LIB mstr_discrete
J 0
(-2950 2500);
PAINT ORANGE (-2950 2500);
DISPLAY INVISIBLE (-2950 2500);
FORCEPROP 0 LAST BOM_COST IO_SLOT
J 0
(-2950 2650);
DISPLAY 1.021277 (-2950 2650);
PAINT ORANGE (-2950 2650);
DISPLAY INVISIBLE (-2950 2650);
FORCEPROP 2 LAST SEC_TYPE 0402
J 0
(-2950 2750);
DISPLAY 1.021277 (-2950 2750);
PAINT ORANGE (-2950 2750);
DISPLAY INVISIBLE (-2950 2750);
FORCEPROP 2 LAST SEC 1
J 0
(-2950 2750);
DISPLAY 0.680851 (-2950 2750);
PAINT MONO (-2950 2750);
DISPLAY INVISIBLE (-2950 2750);
FORCEPROP 2 LAST CDS_LOCATION C9N4
J 1
(-2950 2575);
DISPLAY 0.617021 (-2950 2575);
PAINT AQUA (-2950 2575);
DISPLAY INVISIBLE (-2950 2575);
FORCEPROP 1 LAST PATH I55
J 0
(-2950 2700);
DISPLAY 0.978723 (-2950 2700);
PAINT WHITE (-2950 2700);
DISPLAY INVISIBLE (-2950 2700);
FORCEPROP 0 LAST ROOM IO_SLOT
J 0
(-2950 2700);
DISPLAY 1.021277 (-2950 2700);
PAINT ORANGE (-2950 2700);
DISPLAY INVISIBLE (-2950 2700);
FORCEADD CAP..2
(-2950 2350);
FORCEPROP 1 LAST VALUE 0.22UF
J 2
(-3025 2300);
DISPLAY 0.617021 (-3025 2300);
PAINT SKYBLUE (-3025 2300);
FORCEPROP 1 LASTPIN (-3050 2350) $PN 1
J 0
(-3060 2365);
DISPLAY 0.617021 (-3060 2365);
PAINT ORANGE (-3060 2365);
FORCEPROP 1 LAST LOCATION C9N14
J 1
(-2950 2425);
DISPLAY 0.617021 (-2950 2425);
PAINT AQUA (-2950 2425);
FORCEPROP 1 LASTPIN (-2850 2350) $PN 2
J 0
(-2865 2365);
DISPLAY 0.617021 (-2865 2365);
PAINT ORANGE (-2865 2365);
FORCEPROP 1 LAST VOLTAGE 16V
J 0
(-2850 2325);
DISPLAY 0.617021 (-2850 2325);
PAINT SKYBLUE (-2850 2325);
FORCEPROP 1 LAST MATERIAL X7R
J 0
(-2725 2325);
DISPLAY 0.617021 (-2725 2325);
PAINT SKYBLUE (-2725 2325);
FORCEPROP 1 LAST TOLERANCE 10%
J 2
(-2525 2325);
DISPLAY 0.617021 (-2525 2325);
PAINT SKYBLUE (-2525 2325);
FORCEPROP 1 LAST PART_NUMBER A36096-155
J 1
(-2700 2400);
DISPLAY 0.617021 (-2700 2400);
PAINT BLUE (-2700 2400);
FORCEPROP 1 LAST PACK_TYPE 0402
J 1
(-2425 2325);
DISPLAY 0.617021 (-2425 2325);
PAINT SKYBLUE (-2425 2325);
FORCEPROP 2 LAST CDS_LIB mstr_discrete
J 0
(-2950 2350);
PAINT ORANGE (-2950 2350);
DISPLAY INVISIBLE (-2950 2350);
FORCEPROP 2 LAST CDS_LOCATION C9N14
J 1
(-2950 2425);
DISPLAY 0.617021 (-2950 2425);
PAINT AQUA (-2950 2425);
DISPLAY INVISIBLE (-2950 2425);
FORCEPROP 0 LAST BOM_COST IO_SLOT
J 0
(-2950 2500);
DISPLAY 1.021277 (-2950 2500);
PAINT ORANGE (-2950 2500);
DISPLAY INVISIBLE (-2950 2500);
FORCEPROP 0 LAST ROOM IO_SLOT
J 0
(-2950 2550);
DISPLAY 1.021277 (-2950 2550);
PAINT ORANGE (-2950 2550);
DISPLAY INVISIBLE (-2950 2550);
FORCEPROP 1 LAST PATH I56
J 0
(-2950 2550);
DISPLAY 0.978723 (-2950 2550);
PAINT WHITE (-2950 2550);
DISPLAY INVISIBLE (-2950 2550);
FORCEPROP 2 LAST SEC_TYPE 0402
J 0
(-2950 2600);
DISPLAY 1.021277 (-2950 2600);
PAINT ORANGE (-2950 2600);
DISPLAY INVISIBLE (-2950 2600);
FORCEPROP 2 LAST SEC 1
J 0
(-2950 2600);
DISPLAY 0.680851 (-2950 2600);
PAINT MONO (-2950 2600);
DISPLAY INVISIBLE (-2950 2600);
FORCEADD TAP..1
R 2
(-5400 3550);
FORCEPROP 3 LASTPIN (-5350 3550) SIG_NAME P3E_CPU1_PE3_MP_RXP<8>
J 0
(-5340 3560);
DISPLAY 0.659574 (-5340 3560);
PAINT MONO (-5340 3560);
DISPLAY INVISIBLE (-5340 3560);
FORCEPROP 1 LASTPIN (-5350 3550) BN 8
J 2
(-5338 3558);
DISPLAY 0.617021 (-5338 3558);
PAINT GREEN (-5338 3558);
FORCEPROP 1 LAST HDL_TAP TRUE
J 2
(-5725 3425);
DISPLAY 1.446809 (-5725 3425);
PAINT GREEN (-5725 3425);
DISPLAY INVISIBLE (-5725 3425);
FORCEPROP 1 LAST PATH I57
J 2
(-5398 3550);
DISPLAY 0.872340 (-5398 3550);
PAINT GREEN (-5398 3550);
DISPLAY INVISIBLE (-5398 3550);
FORCEPROP 2 LAST CDS_LIB mstr_standard
J 0
(-5400 3550);
PAINT MONO (-5400 3550);
DISPLAY INVISIBLE (-5400 3550);
FORCEPROP 1 LAST BODY_TYPE PLUMBING
J 2
(-5400 3600);
DISPLAY 1.446809 (-5400 3600);
PAINT GREEN (-5400 3600);
DISPLAY INVISIBLE (-5400 3600);
FORCEADD TAP..1
R 2
(-5650 3600);
FORCEPROP 3 LASTPIN (-5600 3600) SIG_NAME P3E_CPU1_PE3_MP_RXN<8>
J 0
(-5590 3610);
DISPLAY 0.659574 (-5590 3610);
PAINT MONO (-5590 3610);
DISPLAY INVISIBLE (-5590 3610);
FORCEPROP 1 LASTPIN (-5600 3600) BN 8
J 2
(-5588 3608);
DISPLAY 0.617021 (-5588 3608);
PAINT GREEN (-5588 3608);
FORCEPROP 1 LAST HDL_TAP TRUE
J 2
(-5975 3475);
DISPLAY 1.446809 (-5975 3475);
PAINT GREEN (-5975 3475);
DISPLAY INVISIBLE (-5975 3475);
FORCEPROP 1 LAST PATH I58
J 2
(-5648 3600);
DISPLAY 0.872340 (-5648 3600);
PAINT GREEN (-5648 3600);
DISPLAY INVISIBLE (-5648 3600);
FORCEPROP 1 LAST BODY_TYPE PLUMBING
J 2
(-5650 3650);
DISPLAY 1.446809 (-5650 3650);
PAINT GREEN (-5650 3650);
DISPLAY INVISIBLE (-5650 3650);
FORCEPROP 2 LAST CDS_LIB mstr_standard
J 0
(-5650 3600);
PAINT MONO (-5650 3600);
DISPLAY INVISIBLE (-5650 3600);
FORCEADD TAP..1
R 2
(-5400 3400);
FORCEPROP 3 LASTPIN (-5350 3400) SIG_NAME P3E_CPU1_PE3_MP_RXP<9>
J 0
(-5340 3410);
DISPLAY 0.659574 (-5340 3410);
PAINT MONO (-5340 3410);
DISPLAY INVISIBLE (-5340 3410);
FORCEPROP 1 LASTPIN (-5350 3400) BN 9
J 2
(-5338 3408);
DISPLAY 0.617021 (-5338 3408);
PAINT GREEN (-5338 3408);
FORCEPROP 1 LAST HDL_TAP TRUE
J 2
(-5725 3275);
DISPLAY 1.446809 (-5725 3275);
PAINT GREEN (-5725 3275);
DISPLAY INVISIBLE (-5725 3275);
FORCEPROP 2 LAST CDS_LIB mstr_standard
J 0
(-5400 3400);
PAINT MONO (-5400 3400);
DISPLAY INVISIBLE (-5400 3400);
FORCEPROP 1 LAST BODY_TYPE PLUMBING
J 2
(-5400 3450);
DISPLAY 1.446809 (-5400 3450);
PAINT GREEN (-5400 3450);
DISPLAY INVISIBLE (-5400 3450);
FORCEPROP 1 LAST PATH I59
J 2
(-5398 3400);
DISPLAY 0.872340 (-5398 3400);
PAINT GREEN (-5398 3400);
DISPLAY INVISIBLE (-5398 3400);
FORCEADD TAP..6
R 2
(-1475 1650);
FORCEPROP 3 LASTPIN (-1525 1650) SIG_NAME P3E_CPU1_PE3_MP_TXN<10>
J 0
(-1515 1660);
DISPLAY 0.659574 (-1515 1660);
PAINT MONO (-1515 1660);
DISPLAY INVISIBLE (-1515 1660);
FORCEPROP 1 LASTPIN (-1525 1650) BN 10
J 2
(-1473 1658);
DISPLAY 0.617021 (-1473 1658);
PAINT GREEN (-1473 1658);
FORCEPROP 1 LAST HDL_TAP TRUE
J 2
(-1800 1525);
DISPLAY 1.234043 (-1800 1525);
PAINT GREEN (-1800 1525);
DISPLAY INVISIBLE (-1800 1525);
FORCEPROP 1 LAST PATH I6
J 2
(-1473 1650);
DISPLAY 0.872340 (-1473 1650);
PAINT GREEN (-1473 1650);
DISPLAY INVISIBLE (-1473 1650);
FORCEPROP 1 LAST BODY_TYPE PLUMBING
J 2
(-1475 1600);
DISPLAY 1.234043 (-1475 1600);
PAINT GREEN (-1475 1600);
DISPLAY INVISIBLE (-1475 1600);
FORCEPROP 2 LAST CDS_LIB mstr_standard
J 0
(-1475 1650);
PAINT ORANGE (-1475 1650);
DISPLAY INVISIBLE (-1475 1650);
FORCEADD TAP..1
R 2
(-5400 3300);
FORCEPROP 3 LASTPIN (-5350 3300) SIG_NAME P3E_CPU1_PE3_MP_RXP<10>
J 0
(-5340 3310);
DISPLAY 0.659574 (-5340 3310);
PAINT MONO (-5340 3310);
DISPLAY INVISIBLE (-5340 3310);
FORCEPROP 1 LASTPIN (-5350 3300) BN 10
J 2
(-5338 3308);
DISPLAY 0.617021 (-5338 3308);
PAINT GREEN (-5338 3308);
FORCEPROP 1 LAST HDL_TAP TRUE
J 2
(-5725 3175);
DISPLAY 1.446809 (-5725 3175);
PAINT GREEN (-5725 3175);
DISPLAY INVISIBLE (-5725 3175);
FORCEPROP 1 LAST PATH I60
J 2
(-5398 3300);
DISPLAY 0.872340 (-5398 3300);
PAINT GREEN (-5398 3300);
DISPLAY INVISIBLE (-5398 3300);
FORCEPROP 2 LAST CDS_LIB mstr_standard
J 0
(-5400 3300);
PAINT ORANGE (-5400 3300);
DISPLAY INVISIBLE (-5400 3300);
FORCEPROP 1 LAST BODY_TYPE PLUMBING
J 2
(-5400 3350);
DISPLAY 1.446809 (-5400 3350);
PAINT GREEN (-5400 3350);
DISPLAY INVISIBLE (-5400 3350);
FORCEADD TAP..1
R 2
(-5400 3000);
FORCEPROP 3 LASTPIN (-5350 3000) SIG_NAME P3E_CPU1_PE3_MP_RXP<11>
J 0
(-5340 3010);
DISPLAY 0.659574 (-5340 3010);
PAINT MONO (-5340 3010);
DISPLAY INVISIBLE (-5340 3010);
FORCEPROP 1 LASTPIN (-5350 3000) BN 11
J 2
(-5338 3008);
DISPLAY 0.617021 (-5338 3008);
PAINT GREEN (-5338 3008);
FORCEPROP 1 LAST HDL_TAP TRUE
J 2
(-5725 2875);
DISPLAY 1.446809 (-5725 2875);
PAINT GREEN (-5725 2875);
DISPLAY INVISIBLE (-5725 2875);
FORCEPROP 2 LAST CDS_LIB mstr_standard
J 0
(-5400 3000);
PAINT MONO (-5400 3000);
DISPLAY INVISIBLE (-5400 3000);
FORCEPROP 1 LAST PATH I61
J 2
(-5398 3000);
DISPLAY 0.872340 (-5398 3000);
PAINT GREEN (-5398 3000);
DISPLAY INVISIBLE (-5398 3000);
FORCEPROP 1 LAST BODY_TYPE PLUMBING
J 2
(-5400 3050);
DISPLAY 1.446809 (-5400 3050);
PAINT GREEN (-5400 3050);
DISPLAY INVISIBLE (-5400 3050);
FORCEADD TAP..1
R 2
(-5650 3450);
FORCEPROP 3 LASTPIN (-5600 3450) SIG_NAME P3E_CPU1_PE3_MP_RXN<9>
J 0
(-5590 3460);
DISPLAY 0.659574 (-5590 3460);
PAINT MONO (-5590 3460);
DISPLAY INVISIBLE (-5590 3460);
FORCEPROP 1 LASTPIN (-5600 3450) BN 9
J 2
(-5588 3458);
DISPLAY 0.617021 (-5588 3458);
PAINT GREEN (-5588 3458);
FORCEPROP 1 LAST HDL_TAP TRUE
J 2
(-5975 3325);
DISPLAY 1.446809 (-5975 3325);
PAINT GREEN (-5975 3325);
DISPLAY INVISIBLE (-5975 3325);
FORCEPROP 1 LAST PATH I62
J 2
(-5648 3450);
DISPLAY 0.872340 (-5648 3450);
PAINT GREEN (-5648 3450);
DISPLAY INVISIBLE (-5648 3450);
FORCEPROP 1 LAST BODY_TYPE PLUMBING
J 2
(-5650 3500);
DISPLAY 1.446809 (-5650 3500);
PAINT GREEN (-5650 3500);
DISPLAY INVISIBLE (-5650 3500);
FORCEPROP 2 LAST CDS_LIB mstr_standard
J 0
(-5650 3450);
PAINT MONO (-5650 3450);
DISPLAY INVISIBLE (-5650 3450);
FORCEADD TAP..1
R 2
(-5650 3250);
FORCEPROP 3 LASTPIN (-5600 3250) SIG_NAME P3E_CPU1_PE3_MP_RXN<10>
J 0
(-5590 3260);
DISPLAY 0.659574 (-5590 3260);
PAINT MONO (-5590 3260);
DISPLAY INVISIBLE (-5590 3260);
FORCEPROP 1 LASTPIN (-5600 3250) BN 10
J 2
(-5588 3258);
DISPLAY 0.617021 (-5588 3258);
PAINT GREEN (-5588 3258);
FORCEPROP 1 LAST HDL_TAP TRUE
J 2
(-5975 3125);
DISPLAY 1.446809 (-5975 3125);
PAINT GREEN (-5975 3125);
DISPLAY INVISIBLE (-5975 3125);
FORCEPROP 1 LAST PATH I63
J 2
(-5648 3250);
DISPLAY 0.872340 (-5648 3250);
PAINT GREEN (-5648 3250);
DISPLAY INVISIBLE (-5648 3250);
FORCEPROP 2 LAST CDS_LIB mstr_standard
J 0
(-5650 3250);
PAINT ORANGE (-5650 3250);
DISPLAY INVISIBLE (-5650 3250);
FORCEPROP 1 LAST BODY_TYPE PLUMBING
J 2
(-5650 3300);
DISPLAY 1.446809 (-5650 3300);
PAINT GREEN (-5650 3300);
DISPLAY INVISIBLE (-5650 3300);
FORCEADD TAP..1
R 2
(-5650 3050);
FORCEPROP 3 LASTPIN (-5600 3050) SIG_NAME P3E_CPU1_PE3_MP_RXN<11>
J 0
(-5590 3060);
DISPLAY 0.659574 (-5590 3060);
PAINT MONO (-5590 3060);
DISPLAY INVISIBLE (-5590 3060);
FORCEPROP 1 LASTPIN (-5600 3050) BN 11
J 2
(-5588 3058);
DISPLAY 0.617021 (-5588 3058);
PAINT GREEN (-5588 3058);
FORCEPROP 1 LAST HDL_TAP TRUE
J 2
(-5975 2925);
DISPLAY 1.446809 (-5975 2925);
PAINT GREEN (-5975 2925);
DISPLAY INVISIBLE (-5975 2925);
FORCEPROP 1 LAST PATH I64
J 2
(-5648 3050);
DISPLAY 0.872340 (-5648 3050);
PAINT GREEN (-5648 3050);
DISPLAY INVISIBLE (-5648 3050);
FORCEPROP 2 LAST CDS_LIB mstr_standard
J 0
(-5650 3050);
PAINT MONO (-5650 3050);
DISPLAY INVISIBLE (-5650 3050);
FORCEPROP 1 LAST BODY_TYPE PLUMBING
J 2
(-5650 3100);
DISPLAY 1.446809 (-5650 3100);
PAINT GREEN (-5650 3100);
DISPLAY INVISIBLE (-5650 3100);
FORCEADD OFFPAGE..5
(-7275 3925);
FORCEPROP 2 LAST $XR0 66 
J 0
(-7499 3925);
DISPLAY 0.638298 (-7499 3925);
PAINT MONO (-7499 3925);
FORCEPROP 2 LAST PATH I65
J 0
(-7525 3975);
DISPLAY 1.021277 (-7525 3975);
PAINT ORANGE (-7525 3975);
DISPLAY INVISIBLE (-7525 3975);
FORCEPROP 1 LAST COMMENT_BODY TRUE
J 0
(-7175 3850);
DISPLAY 0.872340 (-7175 3850);
PAINT GREEN (-7175 3850);
DISPLAY INVISIBLE (-7175 3850);
FORCEPROP 2 LAST CDS_LIB mstr_standard
J 0
(-7275 3925);
PAINT ORANGE (-7275 3925);
DISPLAY INVISIBLE (-7275 3925);
FORCEPROP 1 LAST OFFPAGE TRUE
J 0
(-6950 3800);
DISPLAY 0.872340 (-6950 3800);
PAINT GREEN (-6950 3800);
DISPLAY INVISIBLE (-6950 3800);
FORCEADD OFFPAGE..5
(-7275 3800);
FORCEPROP 2 LAST $XR0 66 
J 0
(-7499 3800);
DISPLAY 0.638298 (-7499 3800);
PAINT MONO (-7499 3800);
FORCEPROP 2 LAST PATH I66
J 0
(-7525 3850);
DISPLAY 1.021277 (-7525 3850);
PAINT ORANGE (-7525 3850);
DISPLAY INVISIBLE (-7525 3850);
FORCEPROP 1 LAST COMMENT_BODY TRUE
J 0
(-7175 3725);
DISPLAY 0.872340 (-7175 3725);
PAINT GREEN (-7175 3725);
DISPLAY INVISIBLE (-7175 3725);
FORCEPROP 2 LAST CDS_LIB mstr_standard
J 0
(-7275 3800);
PAINT ORANGE (-7275 3800);
DISPLAY INVISIBLE (-7275 3800);
FORCEPROP 1 LAST OFFPAGE TRUE
J 0
(-6950 3675);
DISPLAY 0.872340 (-6950 3675);
PAINT GREEN (-6950 3675);
DISPLAY INVISIBLE (-6950 3675);
FORCEADD TAP..1
R 2
(-5400 2850);
FORCEPROP 3 LASTPIN (-5350 2850) SIG_NAME P3E_CPU1_PE3_MP_RXP<12>
J 0
(-5340 2860);
DISPLAY 0.659574 (-5340 2860);
PAINT MONO (-5340 2860);
DISPLAY INVISIBLE (-5340 2860);
FORCEPROP 1 LASTPIN (-5350 2850) BN 12
J 2
(-5338 2858);
DISPLAY 0.617021 (-5338 2858);
PAINT GREEN (-5338 2858);
FORCEPROP 1 LAST HDL_TAP TRUE
J 2
(-5725 2725);
DISPLAY 1.446809 (-5725 2725);
PAINT GREEN (-5725 2725);
DISPLAY INVISIBLE (-5725 2725);
FORCEPROP 2 LAST CDS_LIB mstr_standard
J 0
(-5400 2850);
PAINT MONO (-5400 2850);
DISPLAY INVISIBLE (-5400 2850);
FORCEPROP 1 LAST PATH I67
J 2
(-5398 2850);
DISPLAY 0.872340 (-5398 2850);
PAINT GREEN (-5398 2850);
DISPLAY INVISIBLE (-5398 2850);
FORCEPROP 1 LAST BODY_TYPE PLUMBING
J 2
(-5400 2900);
DISPLAY 1.446809 (-5400 2900);
PAINT GREEN (-5400 2900);
DISPLAY INVISIBLE (-5400 2900);
FORCEADD TAP..1
R 2
(-5400 2750);
FORCEPROP 3 LASTPIN (-5350 2750) SIG_NAME P3E_CPU1_PE3_MP_RXP<13>
J 0
(-5340 2760);
DISPLAY 0.659574 (-5340 2760);
PAINT MONO (-5340 2760);
DISPLAY INVISIBLE (-5340 2760);
FORCEPROP 1 LASTPIN (-5350 2750) BN 13
J 2
(-5338 2758);
DISPLAY 0.617021 (-5338 2758);
PAINT GREEN (-5338 2758);
FORCEPROP 1 LAST HDL_TAP TRUE
J 2
(-5725 2625);
DISPLAY 1.446809 (-5725 2625);
PAINT GREEN (-5725 2625);
DISPLAY INVISIBLE (-5725 2625);
FORCEPROP 1 LAST PATH I68
J 2
(-5398 2750);
DISPLAY 0.872340 (-5398 2750);
PAINT GREEN (-5398 2750);
DISPLAY INVISIBLE (-5398 2750);
FORCEPROP 2 LAST CDS_LIB mstr_standard
J 0
(-5400 2750);
PAINT ORANGE (-5400 2750);
DISPLAY INVISIBLE (-5400 2750);
FORCEPROP 1 LAST BODY_TYPE PLUMBING
J 2
(-5400 2800);
DISPLAY 1.446809 (-5400 2800);
PAINT GREEN (-5400 2800);
DISPLAY INVISIBLE (-5400 2800);
FORCEADD TAP..1
R 2
(-5400 2550);
FORCEPROP 3 LASTPIN (-5350 2550) SIG_NAME P3E_CPU1_PE3_MP_RXP<14>
J 0
(-5340 2560);
DISPLAY 0.659574 (-5340 2560);
PAINT MONO (-5340 2560);
DISPLAY INVISIBLE (-5340 2560);
FORCEPROP 1 LASTPIN (-5350 2550) BN 14
J 2
(-5338 2558);
DISPLAY 0.617021 (-5338 2558);
PAINT GREEN (-5338 2558);
FORCEPROP 1 LAST HDL_TAP TRUE
J 2
(-5725 2425);
DISPLAY 1.446809 (-5725 2425);
PAINT GREEN (-5725 2425);
DISPLAY INVISIBLE (-5725 2425);
FORCEPROP 1 LAST PATH I69
J 2
(-5398 2550);
DISPLAY 0.872340 (-5398 2550);
PAINT GREEN (-5398 2550);
DISPLAY INVISIBLE (-5398 2550);
FORCEPROP 2 LAST CDS_LIB mstr_standard
J 0
(-5400 2550);
PAINT MONO (-5400 2550);
DISPLAY INVISIBLE (-5400 2550);
FORCEPROP 1 LAST BODY_TYPE PLUMBING
J 2
(-5400 2600);
DISPLAY 1.446809 (-5400 2600);
PAINT GREEN (-5400 2600);
DISPLAY INVISIBLE (-5400 2600);
FORCEADD TAP..6
R 2
(-1725 1800);
FORCEPROP 3 LASTPIN (-1775 1800) SIG_NAME P3E_CPU1_PE3_MP_TXP<9>
J 0
(-1765 1810);
DISPLAY 0.659574 (-1765 1810);
PAINT MONO (-1765 1810);
DISPLAY INVISIBLE (-1765 1810);
FORCEPROP 1 LASTPIN (-1775 1800) BN 9
J 2
(-1723 1808);
DISPLAY 0.617021 (-1723 1808);
PAINT GREEN (-1723 1808);
FORCEPROP 1 LAST HDL_TAP TRUE
J 2
(-2050 1675);
DISPLAY 1.234043 (-2050 1675);
PAINT GREEN (-2050 1675);
DISPLAY INVISIBLE (-2050 1675);
FORCEPROP 1 LAST BODY_TYPE PLUMBING
J 2
(-1725 1750);
DISPLAY 1.234043 (-1725 1750);
PAINT GREEN (-1725 1750);
DISPLAY INVISIBLE (-1725 1750);
FORCEPROP 1 LAST PATH I7
J 2
(-1723 1800);
DISPLAY 0.872340 (-1723 1800);
PAINT GREEN (-1723 1800);
DISPLAY INVISIBLE (-1723 1800);
FORCEPROP 2 LAST CDS_LIB mstr_standard
J 0
(-1725 1800);
PAINT ORANGE (-1725 1800);
DISPLAY INVISIBLE (-1725 1800);
FORCEADD TAP..1
R 2
(-5650 2900);
FORCEPROP 3 LASTPIN (-5600 2900) SIG_NAME P3E_CPU1_PE3_MP_RXN<12>
J 0
(-5590 2910);
DISPLAY 0.659574 (-5590 2910);
PAINT MONO (-5590 2910);
DISPLAY INVISIBLE (-5590 2910);
FORCEPROP 1 LASTPIN (-5600 2900) BN 12
J 2
(-5588 2908);
DISPLAY 0.617021 (-5588 2908);
PAINT GREEN (-5588 2908);
FORCEPROP 1 LAST HDL_TAP TRUE
J 2
(-5975 2775);
DISPLAY 1.446809 (-5975 2775);
PAINT GREEN (-5975 2775);
DISPLAY INVISIBLE (-5975 2775);
FORCEPROP 1 LAST PATH I70
J 2
(-5648 2900);
DISPLAY 0.872340 (-5648 2900);
PAINT GREEN (-5648 2900);
DISPLAY INVISIBLE (-5648 2900);
FORCEPROP 1 LAST BODY_TYPE PLUMBING
J 2
(-5650 2950);
DISPLAY 1.446809 (-5650 2950);
PAINT GREEN (-5650 2950);
DISPLAY INVISIBLE (-5650 2950);
FORCEPROP 2 LAST CDS_LIB mstr_standard
J 0
(-5650 2900);
PAINT MONO (-5650 2900);
DISPLAY INVISIBLE (-5650 2900);
FORCEADD TAP..1
R 2
(-5650 2700);
FORCEPROP 3 LASTPIN (-5600 2700) SIG_NAME P3E_CPU1_PE3_MP_RXN<13>
J 0
(-5590 2710);
DISPLAY 0.659574 (-5590 2710);
PAINT MONO (-5590 2710);
DISPLAY INVISIBLE (-5590 2710);
FORCEPROP 1 LASTPIN (-5600 2700) BN 13
J 2
(-5588 2708);
DISPLAY 0.617021 (-5588 2708);
PAINT GREEN (-5588 2708);
FORCEPROP 1 LAST HDL_TAP TRUE
J 2
(-5975 2575);
DISPLAY 1.446809 (-5975 2575);
PAINT GREEN (-5975 2575);
DISPLAY INVISIBLE (-5975 2575);
FORCEPROP 1 LAST PATH I71
J 2
(-5648 2700);
DISPLAY 0.872340 (-5648 2700);
PAINT GREEN (-5648 2700);
DISPLAY INVISIBLE (-5648 2700);
FORCEPROP 1 LAST BODY_TYPE PLUMBING
J 2
(-5650 2750);
DISPLAY 1.446809 (-5650 2750);
PAINT GREEN (-5650 2750);
DISPLAY INVISIBLE (-5650 2750);
FORCEPROP 2 LAST CDS_LIB mstr_standard
J 0
(-5650 2700);
PAINT ORANGE (-5650 2700);
DISPLAY INVISIBLE (-5650 2700);
FORCEADD TAP..1
R 2
(-5650 2500);
FORCEPROP 3 LASTPIN (-5600 2500) SIG_NAME P3E_CPU1_PE3_MP_RXN<14>
J 0
(-5590 2510);
DISPLAY 0.659574 (-5590 2510);
PAINT MONO (-5590 2510);
DISPLAY INVISIBLE (-5590 2510);
FORCEPROP 1 LASTPIN (-5600 2500) BN 14
J 2
(-5588 2508);
DISPLAY 0.617021 (-5588 2508);
PAINT GREEN (-5588 2508);
FORCEPROP 1 LAST HDL_TAP TRUE
J 2
(-5975 2375);
DISPLAY 1.446809 (-5975 2375);
PAINT GREEN (-5975 2375);
DISPLAY INVISIBLE (-5975 2375);
FORCEPROP 1 LAST PATH I72
J 2
(-5648 2500);
DISPLAY 0.872340 (-5648 2500);
PAINT GREEN (-5648 2500);
DISPLAY INVISIBLE (-5648 2500);
FORCEPROP 2 LAST CDS_LIB mstr_standard
J 0
(-5650 2500);
PAINT MONO (-5650 2500);
DISPLAY INVISIBLE (-5650 2500);
FORCEPROP 1 LAST BODY_TYPE PLUMBING
J 2
(-5650 2550);
DISPLAY 1.446809 (-5650 2550);
PAINT GREEN (-5650 2550);
DISPLAY INVISIBLE (-5650 2550);
FORCEADD TAP..1
R 2
(-5400 2350);
FORCEPROP 3 LASTPIN (-5350 2350) SIG_NAME P3E_CPU1_PE3_MP_RXP<15>
J 0
(-5340 2360);
DISPLAY 0.659574 (-5340 2360);
PAINT MONO (-5340 2360);
DISPLAY INVISIBLE (-5340 2360);
FORCEPROP 1 LASTPIN (-5350 2350) BN 15
J 2
(-5338 2358);
DISPLAY 0.617021 (-5338 2358);
PAINT GREEN (-5338 2358);
FORCEPROP 1 LAST HDL_TAP TRUE
J 2
(-5725 2225);
DISPLAY 1.446809 (-5725 2225);
PAINT GREEN (-5725 2225);
DISPLAY INVISIBLE (-5725 2225);
FORCEPROP 2 LAST CDS_LIB mstr_standard
J 0
(-5400 2350);
PAINT MONO (-5400 2350);
DISPLAY INVISIBLE (-5400 2350);
FORCEPROP 1 LAST BODY_TYPE PLUMBING
J 2
(-5400 2400);
DISPLAY 1.446809 (-5400 2400);
PAINT GREEN (-5400 2400);
DISPLAY INVISIBLE (-5400 2400);
FORCEPROP 1 LAST PATH I73
J 2
(-5398 2350);
DISPLAY 0.872340 (-5398 2350);
PAINT GREEN (-5398 2350);
DISPLAY INVISIBLE (-5398 2350);
FORCEADD TAP..1
R 2
(-5650 2400);
FORCEPROP 3 LASTPIN (-5600 2400) SIG_NAME P3E_CPU1_PE3_MP_RXN<15>
J 0
(-5590 2410);
DISPLAY 0.659574 (-5590 2410);
PAINT MONO (-5590 2410);
DISPLAY INVISIBLE (-5590 2410);
FORCEPROP 1 LASTPIN (-5600 2400) BN 15
J 2
(-5588 2408);
DISPLAY 0.617021 (-5588 2408);
PAINT GREEN (-5588 2408);
FORCEPROP 1 LAST HDL_TAP TRUE
J 2
(-5975 2275);
DISPLAY 1.446809 (-5975 2275);
PAINT GREEN (-5975 2275);
DISPLAY INVISIBLE (-5975 2275);
FORCEPROP 1 LAST PATH I74
J 2
(-5648 2400);
DISPLAY 0.872340 (-5648 2400);
PAINT GREEN (-5648 2400);
DISPLAY INVISIBLE (-5648 2400);
FORCEPROP 1 LAST BODY_TYPE PLUMBING
J 2
(-5650 2450);
DISPLAY 1.446809 (-5650 2450);
PAINT GREEN (-5650 2450);
DISPLAY INVISIBLE (-5650 2450);
FORCEPROP 2 LAST CDS_LIB mstr_standard
J 0
(-5650 2400);
PAINT MONO (-5650 2400);
DISPLAY INVISIBLE (-5650 2400);
FORCEADD TAP..6
R 2
(-1725 1700);
FORCEPROP 3 LASTPIN (-1775 1700) SIG_NAME P3E_CPU1_PE3_MP_TXP<10>
J 0
(-1765 1710);
DISPLAY 0.659574 (-1765 1710);
PAINT MONO (-1765 1710);
DISPLAY INVISIBLE (-1765 1710);
FORCEPROP 1 LASTPIN (-1775 1700) BN 10
J 2
(-1723 1708);
DISPLAY 0.617021 (-1723 1708);
PAINT GREEN (-1723 1708);
FORCEPROP 1 LAST HDL_TAP TRUE
J 2
(-2050 1575);
DISPLAY 1.234043 (-2050 1575);
PAINT GREEN (-2050 1575);
DISPLAY INVISIBLE (-2050 1575);
FORCEPROP 1 LAST PATH I8
J 2
(-1723 1700);
DISPLAY 0.872340 (-1723 1700);
PAINT GREEN (-1723 1700);
DISPLAY INVISIBLE (-1723 1700);
FORCEPROP 1 LAST BODY_TYPE PLUMBING
J 2
(-1725 1650);
DISPLAY 1.234043 (-1725 1650);
PAINT GREEN (-1725 1650);
DISPLAY INVISIBLE (-1725 1650);
FORCEPROP 2 LAST CDS_LIB mstr_standard
J 0
(-1725 1700);
PAINT ORANGE (-1725 1700);
DISPLAY INVISIBLE (-1725 1700);
FORCEADD CAP..2
(-2950 2250);
FORCEPROP 1 LAST VALUE 0.22UF
J 2
(-3000 2225);
DISPLAY 0.617021 (-3000 2225);
PAINT SKYBLUE (-3000 2225);
FORCEPROP 1 LASTPIN (-3050 2250) $PN 1
J 0
(-3060 2265);
DISPLAY 0.617021 (-3060 2265);
PAINT ORANGE (-3060 2265);
FORCEPROP 1 LASTPIN (-2850 2250) $PN 2
J 0
(-2865 2265);
DISPLAY 0.617021 (-2865 2265);
PAINT ORANGE (-2865 2265);
FORCEPROP 1 LAST LOCATION C9N6
J 1
(-2950 2350);
DISPLAY 0.617021 (-2950 2350);
PAINT AQUA (-2950 2350);
FORCEPROP 1 LAST VOLTAGE 16V
J 0
(-2850 2225);
DISPLAY 0.617021 (-2850 2225);
PAINT SKYBLUE (-2850 2225);
FORCEPROP 1 LAST MATERIAL X7R
J 0
(-2725 2225);
DISPLAY 0.617021 (-2725 2225);
PAINT SKYBLUE (-2725 2225);
FORCEPROP 1 LAST TOLERANCE 10%
J 2
(-2525 2225);
DISPLAY 0.617021 (-2525 2225);
PAINT SKYBLUE (-2525 2225);
FORCEPROP 1 LAST PART_NUMBER A36096-155
J 1
(-2650 2275);
DISPLAY 0.617021 (-2650 2275);
PAINT BLUE (-2650 2275);
FORCEPROP 1 LAST PACK_TYPE 0402
J 1
(-2425 2225);
DISPLAY 0.617021 (-2425 2225);
PAINT SKYBLUE (-2425 2225);
FORCEPROP 2 LAST CDS_LIB mstr_discrete
J 0
(-2950 2250);
PAINT ORANGE (-2950 2250);
DISPLAY INVISIBLE (-2950 2250);
FORCEPROP 2 LAST CDS_LOCATION C9N6
J 1
(-2950 2350);
DISPLAY 0.617021 (-2950 2350);
PAINT AQUA (-2950 2350);
DISPLAY INVISIBLE (-2950 2350);
FORCEPROP 0 LAST BOM_COST IO_SLOT
J 0
(-2950 2400);
DISPLAY 1.021277 (-2950 2400);
PAINT ORANGE (-2950 2400);
DISPLAY INVISIBLE (-2950 2400);
FORCEPROP 2 LAST SEC_TYPE 0402
J 0
(-2950 2500);
DISPLAY 1.021277 (-2950 2500);
PAINT ORANGE (-2950 2500);
DISPLAY INVISIBLE (-2950 2500);
FORCEPROP 0 LAST ROOM IO_SLOT
J 0
(-2950 2450);
DISPLAY 1.021277 (-2950 2450);
PAINT ORANGE (-2950 2450);
DISPLAY INVISIBLE (-2950 2450);
FORCEPROP 1 LAST PATH I81
J 0
(-2950 2450);
DISPLAY 0.978723 (-2950 2450);
PAINT WHITE (-2950 2450);
DISPLAY INVISIBLE (-2950 2450);
FORCEPROP 2 LAST SEC 1
J 0
(-2950 2500);
DISPLAY 0.680851 (-2950 2500);
PAINT MONO (-2950 2500);
DISPLAY INVISIBLE (-2950 2500);
FORCEADD TAP..6
R 2
(-1475 2250);
FORCEPROP 3 LASTPIN (-1525 2250) SIG_NAME P3E_CPU1_PE3_MP_TXN<13>
J 0
(-1515 2260);
DISPLAY 0.659574 (-1515 2260);
PAINT MONO (-1515 2260);
DISPLAY INVISIBLE (-1515 2260);
FORCEPROP 1 LASTPIN (-1525 2250) BN 13
J 2
(-1500 2250);
DISPLAY 0.617021 (-1500 2250);
PAINT GREEN (-1500 2250);
FORCEPROP 1 LAST HDL_TAP TRUE
J 2
(-1800 2125);
DISPLAY 1.234043 (-1800 2125);
PAINT GREEN (-1800 2125);
DISPLAY INVISIBLE (-1800 2125);
FORCEPROP 1 LAST PATH I82
J 2
(-1473 2250);
DISPLAY 0.872340 (-1473 2250);
PAINT GREEN (-1473 2250);
DISPLAY INVISIBLE (-1473 2250);
FORCEPROP 1 LAST BODY_TYPE PLUMBING
J 2
(-1475 2200);
DISPLAY 1.234043 (-1475 2200);
PAINT GREEN (-1475 2200);
DISPLAY INVISIBLE (-1475 2200);
FORCEPROP 2 LAST CDS_LIB mstr_standard
J 0
(-1475 2250);
PAINT ORANGE (-1475 2250);
DISPLAY INVISIBLE (-1475 2250);
FORCEADD CAP..2
(-2475 2200);
FORCEPROP 1 LASTPIN (-2575 2200) $PN 1
J 0
(-2585 2215);
DISPLAY 0.617021 (-2585 2215);
PAINT ORANGE (-2585 2215);
FORCEPROP 1 LAST VALUE 0.22UF
J 2
(-2550 2150);
DISPLAY 0.617021 (-2550 2150);
PAINT SKYBLUE (-2550 2150);
FORCEPROP 1 LAST LOCATION C9N5
J 1
(-2475 2275);
DISPLAY 0.617021 (-2475 2275);
PAINT AQUA (-2475 2275);
FORCEPROP 1 LASTPIN (-2375 2200) $PN 2
J 0
(-2390 2215);
DISPLAY 0.617021 (-2390 2215);
PAINT ORANGE (-2390 2215);
FORCEPROP 1 LAST VOLTAGE 16V
J 0
(-2375 2175);
DISPLAY 0.617021 (-2375 2175);
PAINT SKYBLUE (-2375 2175);
FORCEPROP 1 LAST PART_NUMBER A36096-155
J 1
(-2275 2250);
DISPLAY 0.617021 (-2275 2250);
PAINT BLUE (-2275 2250);
FORCEPROP 1 LAST MATERIAL X7R
J 0
(-2250 2175);
DISPLAY 0.617021 (-2250 2175);
PAINT SKYBLUE (-2250 2175);
FORCEPROP 1 LAST TOLERANCE 10%
J 2
(-2050 2175);
DISPLAY 0.617021 (-2050 2175);
PAINT SKYBLUE (-2050 2175);
FORCEPROP 1 LAST PACK_TYPE 0402
J 1
(-1950 2175);
DISPLAY 0.617021 (-1950 2175);
PAINT SKYBLUE (-1950 2175);
FORCEPROP 2 LAST CDS_LIB mstr_discrete
J 0
(-2475 2200);
PAINT ORANGE (-2475 2200);
DISPLAY INVISIBLE (-2475 2200);
FORCEPROP 2 LAST CDS_LOCATION C9N5
J 1
(-2475 2275);
DISPLAY 0.617021 (-2475 2275);
PAINT AQUA (-2475 2275);
DISPLAY INVISIBLE (-2475 2275);
FORCEPROP 2 LAST SEC_TYPE 0402
J 0
(-2475 2450);
DISPLAY 1.021277 (-2475 2450);
PAINT ORANGE (-2475 2450);
DISPLAY INVISIBLE (-2475 2450);
FORCEPROP 0 LAST BOM_COST IO_SLOT
J 0
(-2475 2350);
DISPLAY 1.021277 (-2475 2350);
PAINT ORANGE (-2475 2350);
DISPLAY INVISIBLE (-2475 2350);
FORCEPROP 2 LAST SEC 1
J 0
(-2475 2450);
DISPLAY 0.680851 (-2475 2450);
PAINT MONO (-2475 2450);
DISPLAY INVISIBLE (-2475 2450);
FORCEPROP 1 LAST PATH I83
J 0
(-2475 2400);
DISPLAY 0.978723 (-2475 2400);
PAINT WHITE (-2475 2400);
DISPLAY INVISIBLE (-2475 2400);
FORCEPROP 0 LAST ROOM IO_SLOT
J 0
(-2475 2400);
DISPLAY 1.021277 (-2475 2400);
PAINT ORANGE (-2475 2400);
DISPLAY INVISIBLE (-2475 2400);
FORCEADD TAP..6
R 2
(-1725 2200);
FORCEPROP 3 LASTPIN (-1775 2200) SIG_NAME P3E_CPU1_PE3_MP_TXP<13>
J 0
(-1765 2210);
DISPLAY 0.659574 (-1765 2210);
PAINT MONO (-1765 2210);
DISPLAY INVISIBLE (-1765 2210);
FORCEPROP 1 LASTPIN (-1775 2200) BN 13
J 2
(-1723 2208);
DISPLAY 0.617021 (-1723 2208);
PAINT GREEN (-1723 2208);
FORCEPROP 1 LAST HDL_TAP TRUE
J 2
(-2050 2075);
DISPLAY 1.234043 (-2050 2075);
PAINT GREEN (-2050 2075);
DISPLAY INVISIBLE (-2050 2075);
FORCEPROP 1 LAST PATH I84
J 2
(-1723 2200);
DISPLAY 0.872340 (-1723 2200);
PAINT GREEN (-1723 2200);
DISPLAY INVISIBLE (-1723 2200);
FORCEPROP 1 LAST BODY_TYPE PLUMBING
J 2
(-1725 2150);
DISPLAY 1.234043 (-1725 2150);
PAINT GREEN (-1725 2150);
DISPLAY INVISIBLE (-1725 2150);
FORCEPROP 2 LAST CDS_LIB mstr_standard
J 0
(-1725 2200);
PAINT ORANGE (-1725 2200);
DISPLAY INVISIBLE (-1725 2200);
FORCEADD OFFPAGE..4
(-2775 3400);
FORCEPROP 2 LAST $XR0 138 
J 0
(-2589 3400);
DISPLAY 0.638298 (-2589 3400);
PAINT MONO (-2589 3400);
FORCEPROP 2 LAST $XR1 160 
J 0
(-2469 3400);
DISPLAY 0.638298 (-2469 3400);
PAINT MONO (-2469 3400);
FORCEPROP 2 LAST $XR2 156 
J 0
(-2349 3400);
DISPLAY 0.638298 (-2349 3400);
PAINT MONO (-2349 3400);
FORCEPROP 2 LAST $XR3 182 
J 0
(-2229 3400);
DISPLAY 0.638298 (-2229 3400);
PAINT MONO (-2229 3400);
FORCEPROP 2 LAST $XR5 ?
J 0
(-2229 3400);
DISPLAY 0.638298 (-2229 3400);
PAINT MONO (-2229 3400);
FORCEPROP 2 LAST $XR4 ?
J 0
(-2229 3400);
DISPLAY 0.638298 (-2229 3400);
PAINT MONO (-2229 3400);
FORCEPROP 1 LAST COMMENT_BODY TRUE
J 0
(-2800 3300);
DISPLAY 0.872340 (-2800 3300);
PAINT GREEN (-2800 3300);
DISPLAY INVISIBLE (-2800 3300);
FORCEPROP 2 LAST CDS_LIB mstr_standard
J 0
(-2775 3400);
PAINT MONO (-2775 3400);
DISPLAY INVISIBLE (-2775 3400);
FORCEPROP 2 LAST PATH I85
J 0
(-2600 3475);
DISPLAY 1.021277 (-2600 3475);
PAINT ORANGE (-2600 3475);
DISPLAY INVISIBLE (-2600 3475);
FORCEPROP 1 LAST OFFPAGE TRUE
J 0
(-2450 3275);
DISPLAY 0.872340 (-2450 3275);
PAINT GREEN (-2450 3275);
DISPLAY INVISIBLE (-2450 3275);
FORCEADD OFFPAGE..6
R 2
(-2775 3450);
FORCEPROP 2 LAST $XR0 138 
J 0
(-2561 3450);
DISPLAY 0.638298 (-2561 3450);
PAINT MONO (-2561 3450);
FORCEPROP 2 LAST $XR1 156 
J 0
(-2441 3450);
DISPLAY 0.638298 (-2441 3450);
PAINT MONO (-2441 3450);
FORCEPROP 2 LAST $XR2 160 
J 0
(-2321 3450);
DISPLAY 0.638298 (-2321 3450);
PAINT MONO (-2321 3450);
FORCEPROP 2 LAST $XR3 182 
J 0
(-2201 3450);
DISPLAY 0.638298 (-2201 3450);
PAINT MONO (-2201 3450);
FORCEPROP 2 LAST $XR5 ?
J 0
(-2201 3450);
DISPLAY 0.638298 (-2201 3450);
PAINT MONO (-2201 3450);
FORCEPROP 2 LAST $XR4 ?
J 0
(-2201 3450);
DISPLAY 0.638298 (-2201 3450);
PAINT MONO (-2201 3450);
FORCEPROP 1 LAST OFFPAGE TRUE
J 2
(-3100 3325);
DISPLAY 0.872340 (-3100 3325);
PAINT GREEN (-3100 3325);
DISPLAY INVISIBLE (-3100 3325);
FORCEPROP 1 LAST COMMENT_BODY TRUE
J 2
(-2875 3375);
DISPLAY 0.872340 (-2875 3375);
PAINT GREEN (-2875 3375);
DISPLAY INVISIBLE (-2875 3375);
FORCEPROP 2 LAST CDS_LIB mstr_standard
J 0
(-2775 3450);
PAINT MONO (-2775 3450);
DISPLAY INVISIBLE (-2775 3450);
FORCEPROP 2 LAST PATH I86
J 0
(-2600 3525);
DISPLAY 1.021277 (-2600 3525);
PAINT ORANGE (-2600 3525);
DISPLAY INVISIBLE (-2600 3525);
FORCEADD OFFPAGE..1
R 2
(-2775 3550);
FORCEPROP 2 LAST $XR0 120 
J 0
(-2589 3550);
DISPLAY 0.638298 (-2589 3550);
PAINT MONO (-2589 3550);
FORCEPROP 2 LAST $XR1 133 
J 0
(-2469 3550);
DISPLAY 0.638298 (-2469 3550);
PAINT MONO (-2469 3550);
FORCEPROP 2 LAST $XR2 145 
J 0
(-2349 3550);
DISPLAY 0.638298 (-2349 3550);
PAINT MONO (-2349 3550);
FORCEPROP 2 LAST $XR3 182 
J 0
(-2229 3550);
DISPLAY 0.638298 (-2229 3550);
PAINT MONO (-2229 3550);
FORCEPROP 1 LAST OFFPAGE TRUE
J 2
(-3100 3425);
DISPLAY 0.872340 (-3100 3425);
PAINT GREEN (-3100 3425);
DISPLAY INVISIBLE (-3100 3425);
FORCEPROP 1 LAST COMMENT_BODY TRUE
J 2
(-2900 3450);
DISPLAY 0.872340 (-2900 3450);
PAINT GREEN (-2900 3450);
DISPLAY INVISIBLE (-2900 3450);
FORCEPROP 2 LAST CDS_LIB mstr_standard
J 0
(-2775 3550);
PAINT MONO (-2775 3550);
DISPLAY INVISIBLE (-2775 3550);
FORCEPROP 2 LAST PATH I87
J 0
(-2600 3625);
DISPLAY 1.021277 (-2600 3625);
PAINT ORANGE (-2600 3625);
DISPLAY INVISIBLE (-2600 3625);
FORCEADD CAP..2
(-2475 2000);
FORCEPROP 1 LASTPIN (-2575 2000) $PN 1
J 0
(-2585 2015);
DISPLAY 0.617021 (-2585 2015);
PAINT ORANGE (-2585 2015);
FORCEPROP 1 LAST VALUE 0.22UF
J 2
(-2525 1975);
DISPLAY 0.617021 (-2525 1975);
PAINT SKYBLUE (-2525 1975);
FORCEPROP 1 LASTPIN (-2375 2000) $PN 2
J 0
(-2390 2015);
DISPLAY 0.617021 (-2390 2015);
PAINT ORANGE (-2390 2015);
FORCEPROP 1 LAST VOLTAGE 16V
J 0
(-2375 1975);
DISPLAY 0.617021 (-2375 1975);
PAINT SKYBLUE (-2375 1975);
FORCEPROP 1 LAST MATERIAL X7R
J 0
(-2250 1975);
DISPLAY 0.617021 (-2250 1975);
PAINT SKYBLUE (-2250 1975);
FORCEPROP 1 LAST TOLERANCE 10%
J 2
(-2050 1975);
DISPLAY 0.617021 (-2050 1975);
PAINT SKYBLUE (-2050 1975);
FORCEPROP 1 LAST LOCATION C9N18
J 1
(-2475 2075);
DISPLAY 0.617021 (-2475 2075);
PAINT AQUA (-2475 2075);
FORCEPROP 1 LAST PART_NUMBER A36096-155
J 1
(-2175 2025);
DISPLAY 0.617021 (-2175 2025);
PAINT BLUE (-2175 2025);
FORCEPROP 1 LAST PACK_TYPE 0402
J 1
(-1950 1975);
DISPLAY 0.617021 (-1950 1975);
PAINT SKYBLUE (-1950 1975);
FORCEPROP 2 LAST CDS_LIB mstr_discrete
J 0
(-2475 2000);
PAINT ORANGE (-2475 2000);
DISPLAY INVISIBLE (-2475 2000);
FORCEPROP 2 LAST SEC_TYPE 0402
J 0
(-2475 2250);
DISPLAY 1.021277 (-2475 2250);
PAINT ORANGE (-2475 2250);
DISPLAY INVISIBLE (-2475 2250);
FORCEPROP 0 LAST BOM_COST IO_SLOT
J 0
(-2475 2150);
DISPLAY 1.021277 (-2475 2150);
PAINT ORANGE (-2475 2150);
DISPLAY INVISIBLE (-2475 2150);
FORCEPROP 2 LAST SEC 1
J 0
(-2475 2250);
DISPLAY 0.680851 (-2475 2250);
PAINT MONO (-2475 2250);
DISPLAY INVISIBLE (-2475 2250);
FORCEPROP 2 LAST CDS_LOCATION C9N18
J 1
(-2475 2075);
DISPLAY 0.617021 (-2475 2075);
PAINT AQUA (-2475 2075);
DISPLAY INVISIBLE (-2475 2075);
FORCEPROP 1 LAST PATH I9
J 0
(-2475 2200);
DISPLAY 0.978723 (-2475 2200);
PAINT WHITE (-2475 2200);
DISPLAY INVISIBLE (-2475 2200);
FORCEPROP 0 LAST ROOM IO_SLOT
J 0
(-2475 2200);
DISPLAY 1.021277 (-2475 2200);
PAINT ORANGE (-2475 2200);
DISPLAY INVISIBLE (-2475 2200);
FORCEADD OFFPAGE..2
(-2800 3300);
FORCEPROP 2 LAST $XR0 133 
J 0
(-2611 3300);
DISPLAY 0.638298 (-2611 3300);
PAINT MONO (-2611 3300);
FORCEPROP 2 LAST $XR1 119 
J 0
(-2491 3300);
DISPLAY 0.638298 (-2491 3300);
PAINT MONO (-2491 3300);
FORCEPROP 2 LAST $XR2 147 
J 0
(-2371 3300);
DISPLAY 0.638298 (-2371 3300);
PAINT MONO (-2371 3300);
FORCEPROP 1 LAST COMMENT_BODY TRUE
J 0
(-2845 3205);
DISPLAY 0.872340 (-2845 3205);
PAINT GREEN (-2845 3205);
DISPLAY INVISIBLE (-2845 3205);
FORCEPROP 2 LAST CDS_LIB mstr_standard
J 0
(-2800 3300);
PAINT MONO (-2800 3300);
DISPLAY INVISIBLE (-2800 3300);
FORCEPROP 2 LAST PATH I91
J 0
(-2625 3375);
DISPLAY 1.021277 (-2625 3375);
PAINT ORANGE (-2625 3375);
DISPLAY INVISIBLE (-2625 3375);
FORCEPROP 1 LAST OFFPAGE TRUE
J 0
(-2475 3175);
DISPLAY 0.872340 (-2475 3175);
PAINT GREEN (-2475 3175);
DISPLAY INVISIBLE (-2475 3175);
FORCEADD OFFPAGE..2
(-2800 3250);
FORCEPROP 2 LAST $XR0 133 
J 0
(-2611 3250);
DISPLAY 0.638298 (-2611 3250);
PAINT MONO (-2611 3250);
FORCEPROP 2 LAST $XR1 182 
J 0
(-2491 3250);
DISPLAY 0.638298 (-2491 3250);
PAINT MONO (-2491 3250);
FORCEPROP 2 LAST $XR2 119 
J 0
(-2371 3250);
DISPLAY 0.638298 (-2371 3250);
PAINT MONO (-2371 3250);
FORCEPROP 2 LAST $XR3 147 
J 0
(-2251 3250);
DISPLAY 0.638298 (-2251 3250);
PAINT MONO (-2251 3250);
FORCEPROP 1 LAST COMMENT_BODY TRUE
J 0
(-2845 3155);
DISPLAY 0.872340 (-2845 3155);
PAINT GREEN (-2845 3155);
DISPLAY INVISIBLE (-2845 3155);
FORCEPROP 2 LAST CDS_LIB mstr_standard
J 0
(-2800 3250);
PAINT MONO (-2800 3250);
DISPLAY INVISIBLE (-2800 3250);
FORCEPROP 2 LAST PATH I92
J 0
(-2625 3325);
DISPLAY 1.021277 (-2625 3325);
PAINT ORANGE (-2625 3325);
DISPLAY INVISIBLE (-2625 3325);
FORCEPROP 1 LAST OFFPAGE TRUE
J 0
(-2475 3125);
DISPLAY 0.872340 (-2475 3125);
PAINT GREEN (-2475 3125);
DISPLAY INVISIBLE (-2475 3125);
FORCEADD OFFPAGE..3
(-2800 3050);
FORCEPROP 2 LAST $XR0 163 
J 0
(-2586 3050);
DISPLAY 0.638298 (-2586 3050);
PAINT MONO (-2586 3050);
FORCEPROP 1 LAST COMMENT_BODY TRUE
J 0
(-2850 2950);
DISPLAY 0.872340 (-2850 2950);
PAINT GREEN (-2850 2950);
DISPLAY INVISIBLE (-2850 2950);
FORCEPROP 1 LAST OFFPAGE TRUE
J 0
(-2475 2925);
DISPLAY 0.872340 (-2475 2925);
PAINT GREEN (-2475 2925);
DISPLAY INVISIBLE (-2475 2925);
FORCEPROP 2 LAST CDS_LIB mstr_standard
J 0
(-2800 3050);
PAINT MONO (-2800 3050);
DISPLAY INVISIBLE (-2800 3050);
FORCEPROP 2 LAST PATH I94
J 0
(-2600 3125);
DISPLAY 1.021277 (-2600 3125);
PAINT ORANGE (-2600 3125);
DISPLAY INVISIBLE (-2600 3125);
FORCEADD OFFPAGE..1
R 2
(-2800 3000);
FORCEPROP 2 LAST $XR0 163 
J 0
(-2584 3000);
DISPLAY 0.638298 (-2584 3000);
PAINT MONO (-2584 3000);
FORCEPROP 1 LAST OFFPAGE TRUE
J 2
(-3125 2875);
DISPLAY 0.872340 (-3125 2875);
PAINT GREEN (-3125 2875);
DISPLAY INVISIBLE (-3125 2875);
FORCEPROP 1 LAST COMMENT_BODY TRUE
J 2
(-2925 2900);
DISPLAY 0.872340 (-2925 2900);
PAINT GREEN (-2925 2900);
DISPLAY INVISIBLE (-2925 2900);
FORCEPROP 2 LAST CDS_LIB mstr_standard
J 0
(-2800 3000);
PAINT MONO (-2800 3000);
DISPLAY INVISIBLE (-2800 3000);
FORCEPROP 2 LAST PATH I95
J 0
(-2625 3075);
DISPLAY 1.021277 (-2625 3075);
PAINT ORANGE (-2625 3075);
DISPLAY INVISIBLE (-2625 3075);
FORCEADD OFFPAGE..5
(-6400 1950);
FORCEPROP 2 LAST $XR0 119 
J 0
(-6685 1950);
DISPLAY 0.638298 (-6685 1950);
PAINT MONO (-6685 1950);
FORCEPROP 2 LAST $XR1 145 
J 0
(-6805 1950);
DISPLAY 0.638298 (-6805 1950);
PAINT MONO (-6805 1950);
FORCEPROP 2 LAST CDS_LIB mstr_standard
J 0
(-6400 1950);
PAINT MONO (-6400 1950);
DISPLAY INVISIBLE (-6400 1950);
FORCEPROP 1 LAST COMMENT_BODY TRUE
J 0
(-6300 1875);
DISPLAY 0.872340 (-6300 1875);
PAINT GREEN (-6300 1875);
DISPLAY INVISIBLE (-6300 1875);
FORCEPROP 2 LAST PATH I96
J 0
(-6350 2025);
DISPLAY 1.021277 (-6350 2025);
PAINT ORANGE (-6350 2025);
DISPLAY INVISIBLE (-6350 2025);
FORCEPROP 1 LAST OFFPAGE TRUE
J 0
(-6075 1825);
DISPLAY 0.872340 (-6075 1825);
PAINT GREEN (-6075 1825);
DISPLAY INVISIBLE (-6075 1825);
FORCEADD RES..1
(-6550 875);
FORCEPROP 1 LAST LOCATION R1C11
J 2
(-6675 875);
DISPLAY 0.617021 (-6675 875);
PAINT AQUA (-6675 875);
FORCEPROP 1 LAST WATTAGE 1/16W
J 2
(-6675 825);
DISPLAY 0.617021 (-6675 825);
PAINT SKYBLUE (-6675 825);
FORCEPROP 1 LAST VALUE 0.0
J 2
(-6575 825);
DISPLAY 0.617021 (-6575 825);
PAINT SKYBLUE (-6575 825);
FORCEPROP 1 LASTPIN (-6650 875) $PN 1
J 0
(-6638 887);
DISPLAY 0.617021 (-6638 887);
PAINT ORANGE (-6638 887);
FORCEPROP 1 LAST TOLERANCE 5%
J 0
(-6500 825);
DISPLAY 0.617021 (-6500 825);
PAINT SKYBLUE (-6500 825);
FORCEPROP 1 LASTPIN (-6450 875) $PN 2
J 0
(-6488 887);
DISPLAY 0.617021 (-6488 887);
PAINT ORANGE (-6488 887);
FORCEPROP 1 LAST PART_NUMBER G21497-005
J 2
(-6200 875);
DISPLAY 0.617021 (-6200 875);
PAINT BLUE (-6200 875);
FORCEPROP 1 LAST MATERIAL EMPTY
J 0
(-6425 825);
DISPLAY 0.617021 (-6425 825);
PAINT RED (-6425 825);
FORCEPROP 1 LAST PACK_TYPE 0402
J 0
(-6300 825);
DISPLAY 0.617021 (-6300 825);
PAINT SKYBLUE (-6300 825);
FORCEPROP 2 LAST CDS_LOCATION R1C11
J 2
(-6675 875);
DISPLAY 0.617021 (-6675 875);
PAINT AQUA (-6675 875);
DISPLAY INVISIBLE (-6675 875);
FORCEPROP 2 LAST CDS_LIB mstr_discrete
J 0
(-6550 875);
PAINT ORANGE (-6550 875);
DISPLAY INVISIBLE (-6550 875);
FORCEPROP 0 LAST ROOM IO_SLOT
J 0
(-6475 975);
DISPLAY 1.021277 (-6475 975);
PAINT ORANGE (-6475 975);
DISPLAY INVISIBLE (-6475 975);
FORCEPROP 1 LAST PATH I97
J 0
(-6600 1025);
DISPLAY 0.978723 (-6600 1025);
PAINT WHITE (-6600 1025);
DISPLAY INVISIBLE (-6600 1025);
FORCEPROP 2 LAST NO_XNET_CONNECTION 1
J 0
(-6600 1075);
PAINT MONO (-6600 1075);
DISPLAY INVISIBLE (-6600 1075);
FORCEPROP 2 LAST SEC 1
J 0
(-6600 1075);
DISPLAY 0.680851 (-6600 1075);
PAINT MONO (-6600 1075);
DISPLAY INVISIBLE (-6600 1075);
FORCEPROP 2 LAST SEC_TYPE 0402
J 0
(-6600 1075);
DISPLAY 1.021277 (-6600 1075);
PAINT ORANGE (-6600 1075);
DISPLAY INVISIBLE (-6600 1075);
FORCEADD OFFPAGE..2
(-5525 875);
FORCEPROP 2 LAST $XR0 181 
J 0
(-5336 875);
DISPLAY 0.638298 (-5336 875);
PAINT MONO (-5336 875);
FORCEPROP 1 LAST COMMENT_BODY TRUE
J 0
(-5570 780);
DISPLAY 0.872340 (-5570 780);
PAINT GREEN (-5570 780);
DISPLAY INVISIBLE (-5570 780);
FORCEPROP 2 LAST CDS_LIB mstr_standard
J 0
(-5525 875);
PAINT ORANGE (-5525 875);
DISPLAY INVISIBLE (-5525 875);
FORCEPROP 2 LAST PATH I98
J 0
(-5475 950);
DISPLAY 1.021277 (-5475 950);
PAINT ORANGE (-5475 950);
DISPLAY INVISIBLE (-5475 950);
FORCEPROP 1 LAST OFFPAGE TRUE
J 0
(-5200 750);
DISPLAY 0.872340 (-5200 750);
PAINT GREEN (-5200 750);
DISPLAY INVISIBLE (-5200 750);
FORCEADD OFFPAGE..1
(-7425 875);
FORCEPROP 2 LAST $XR0 138 
J 0
(-7677 875);
DISPLAY 0.638298 (-7677 875);
PAINT MONO (-7677 875);
FORCEPROP 2 LAST $XR1 160 
J 0
(-7797 875);
DISPLAY 0.638298 (-7797 875);
PAINT MONO (-7797 875);
FORCEPROP 2 LAST $XR2 156 
J 0
(-7917 875);
DISPLAY 0.638298 (-7917 875);
PAINT MONO (-7917 875);
FORCEPROP 2 LAST $XR3 182 
J 0
(-7677 839);
DISPLAY 0.638298 (-7677 839);
PAINT MONO (-7677 839);
FORCEPROP 2 LAST $XR5 ?
J 0
(-7677 839);
DISPLAY 0.638298 (-7677 839);
PAINT MONO (-7677 839);
FORCEPROP 2 LAST $XR4 ?
J 0
(-7677 839);
DISPLAY 0.638298 (-7677 839);
PAINT MONO (-7677 839);
FORCEPROP 2 LAST CDS_LIB mstr_standard
J 0
(-7425 875);
PAINT ORANGE (-7425 875);
DISPLAY INVISIBLE (-7425 875);
FORCEPROP 2 LAST PATH I99
J 0
(-7375 950);
DISPLAY 1.021277 (-7375 950);
PAINT ORANGE (-7375 950);
DISPLAY INVISIBLE (-7375 950);
FORCEPROP 1 LAST COMMENT_BODY TRUE
J 0
(-7300 775);
DISPLAY 0.872340 (-7300 775);
PAINT GREEN (-7300 775);
DISPLAY INVISIBLE (-7300 775);
FORCEPROP 1 LAST OFFPAGE TRUE
J 0
(-7100 750);
DISPLAY 0.872340 (-7100 750);
PAINT GREEN (-7100 750);
DISPLAY INVISIBLE (-7100 750);
FORCEADD DESIGN_NOTE..1
(-7425 1350);
FORCEPROP 0 LAST L3 CREEK COMPATABILITY
J 0
(-7625 1125);
DISPLAY 1.021277 (-7625 1125);
PAINT ORANGE (-7625 1125);
FORCEPROP 0 LAST L5 THESE RESISTORS
J 0
(-7625 1025);
DISPLAY 1.021277 (-7625 1025);
PAINT ORANGE (-7625 1025);
FORCEPROP 0 LAST L4 WHEN USING WITH BULLDOG CREEK, POPULATE
J 0
(-7625 1075);
DISPLAY 1.021277 (-7625 1075);
PAINT ORANGE (-7625 1075);
FORCEPROP 0 LAST L2 FROM AIRMAX B TO AIRMAX A FOR BULLDOG
J 0
(-7625 1175);
DISPLAY 1.021277 (-7625 1175);
PAINT ORANGE (-7625 1175);
FORCEPROP 0 LAST L1 THESE RESISTORS USED TO STEER SIGNALS
J 0
(-7625 1225);
DISPLAY 1.021277 (-7625 1225);
PAINT ORANGE (-7625 1225);
FORCEPROP 1 LAST COMMENT_BODY TRUE
J 0
(-7400 1450);
DISPLAY 0.978723 (-7400 1450);
PAINT ORANGE (-7400 1450);
DISPLAY INVISIBLE (-7400 1450);
FORCEPROP 2 LAST CDS_LIB mstr_symbols
J 0
(-7425 1350);
PAINT ORANGE (-7425 1350);
DISPLAY INVISIBLE (-7425 1350);
FORCEADD DNS..2
(-6545 745);
PAINT RED (-6545 745);
FORCEPROP 1 LAST COMMENT_BODY TRUE
R 1
J 0
(-6470 520);
DISPLAY 0.872340 (-6470 520);
PAINT GREEN (-6470 520);
DISPLAY INVISIBLE (-6470 520);
FORCEPROP 2 LAST CDS_LIB mstr_misc
J 0
(-6545 745);
PAINT ORANGE (-6545 745);
DISPLAY INVISIBLE (-6545 745);
FORCEADD DNS..2
(-6545 620);
PAINT RED (-6545 620);
FORCEPROP 1 LAST COMMENT_BODY TRUE
R 1
J 0
(-6470 395);
DISPLAY 0.872340 (-6470 395);
PAINT GREEN (-6470 395);
DISPLAY INVISIBLE (-6470 395);
FORCEPROP 2 LAST CDS_LIB mstr_misc
J 0
(-6545 620);
PAINT ORANGE (-6545 620);
DISPLAY INVISIBLE (-6545 620);
FORCEADD DNS..2
(-6545 495);
PAINT RED (-6545 495);
FORCEPROP 1 LAST COMMENT_BODY TRUE
R 1
J 0
(-6470 270);
DISPLAY 0.872340 (-6470 270);
PAINT GREEN (-6470 270);
DISPLAY INVISIBLE (-6470 270);
FORCEPROP 2 LAST CDS_LIB mstr_misc
J 0
(-6545 495);
PAINT ORANGE (-6545 495);
DISPLAY INVISIBLE (-6545 495);
FORCEADD DNS..2
(-6545 345);
PAINT RED (-6545 345);
FORCEPROP 1 LAST COMMENT_BODY TRUE
R 1
J 0
(-6470 120);
DISPLAY 0.872340 (-6470 120);
PAINT GREEN (-6470 120);
DISPLAY INVISIBLE (-6470 120);
FORCEPROP 2 LAST CDS_LIB mstr_misc
J 0
(-6545 345);
PAINT ORANGE (-6545 345);
DISPLAY INVISIBLE (-6545 345);
FORCEADD DNS..2
(-6545 870);
PAINT RED (-6545 870);
FORCEPROP 1 LAST COMMENT_BODY TRUE
R 1
J 0
(-6470 645);
DISPLAY 0.872340 (-6470 645);
PAINT GREEN (-6470 645);
DISPLAY INVISIBLE (-6470 645);
FORCEPROP 2 LAST CDS_LIB mstr_misc
J 0
(-6545 870);
PAINT ORANGE (-6545 870);
DISPLAY INVISIBLE (-6545 870);
FORCEADD INTEL_CORP_BPAGE..1
(0 0);
FORCEPROP 1 LAST CDS_CON_LAST_MODIFIED Tue Dec 01 11:52:15 2015
J 0
(-1425 325);
DISPLAY 0.659574 (-1425 325);
PAINT GREEN (-1425 325);
DISPLAY INVISIBLE (-1425 325);
FORCEPROP 1 LAST CUSTOM_TXT_CDS <CURRENT_DESIGN_SHEET> OF <TOTAL_DESIGN_SHEETS>
J 0
(-500 25);
PAINT GREEN (-500 25);
FORCEPROP 1 LAST CUSTOM_TXT_CDS <CON_LAST_MODIFIED>
J 0
(-1925 350);
PAINT GREEN (-1925 350);
FORCEPROP 2 LAST CUSTOM_TXT_CDS <XR_PAGE_TITLE>
J 0
(-7890 5250);
DISPLAY 0.638298 (-7890 5250);
PAINT PINK (-7890 5250);
DISPLAY INVISIBLE (-7890 5250);
FORCEPROP 1 LAST SCH_TITLE AIRMAX 1X8 MID-PLANE CONNECTOR B
J 0
(-7950 50);
DISPLAY 1.212766 (-7950 50);
PAINT WHITE (-7950 50);
FORCEPROP 1 LAST SCH_ADDRESS1 2200 Mission College Blvd.
J 0
(-3975 125);
DISPLAY 0.617021 (-3975 125);
PAINT GREEN (-3975 125);
FORCEPROP 1 LAST SCH_ADDRESS2 P.O. BOX 58119
J 0
(-3975 75);
DISPLAY 0.617021 (-3975 75);
PAINT GREEN (-3975 75);
FORCEPROP 1 LAST SCH_ADDRESS3 Santa Clara, CA 95052-8119
J 0
(-3975 25);
DISPLAY 0.617021 (-3975 25);
PAINT GREEN (-3975 25);
FORCEPROP 1 LAST SCH_NUMBER H4694802
J 0
(-1300 150);
DISPLAY 1.212766 (-1300 150);
PAINT YELLOW (-1300 150);
FORCEPROP 1 LAST SCH_DEPT BESD
J 1
(-4450 100);
DISPLAY 1.212766 (-4450 100);
PAINT YELLOW (-4450 100);
FORCEPROP 1 LAST SCH_REV 2.420
J 0
(-250 150);
DISPLAY 0.978723 (-250 150);
PAINT YELLOW (-250 150);
FORCEPROP 2 LAST PAGE_BORDER TRUE
J 0
(-7890 5250);
DISPLAY 0.425532 (-7890 5250);
PAINT PINK (-7890 5250);
DISPLAY INVISIBLE (-7890 5250);
FORCEPROP 2 LAST CDS_LIB mstr_symbols
J 0
(0 0);
DISPLAY 0.659574 (0 0);
PAINT ORANGE (0 0);
DISPLAY INVISIBLE (0 0);
FORCEPROP 1 LAST COMMENT_BODY TRUE
J 0
(10 10);
DISPLAY 0.297872 (10 10);
PAINT GREEN (10 10);
DISPLAY INVISIBLE (10 10);
FORCEPROP 2 LAST CDS_XR_PAGE_TITLE CR-182 : @BASEBOARD_FAB2_LIB.BASEBOARD_FAB2(SCH_1):PAGE182
J 0
(-7890 5250);
DISPLAY 0.638298 (-7890 5250);
PAINT PINK (-7890 5250);
DISPLAY INVISIBLE (-7890 5250);
WIRE 17 -1 (-5450 2575)(-5450 2375);
WIRE 17 -1 (-5450 2775)(-5450 2575);
WIRE 17 -1 (-5450 2875)(-5450 2775);
WIRE 17 -1 (-5450 3025)(-5450 2875);
WIRE 17 -1 (-5450 3025)(-5450 3325);
WIRE 17 -1 (-5450 3325)(-5450 3425);
WIRE 17 -1 (-5450 3575)(-5450 3425);
WIRE 17 -1 (-5450 3925)(-5450 3575);
WIRE 17 -1 (-5450 3925)(-7225 3925);
FORCEPROP 2 LAST SIG_NAME P3E_CPU1_PE3_MP_RXP<15:8>
J 0
(-7210 3935);
DISPLAY 0.617021 (-7210 3935);
PAINT ORANGE (-7210 3935);
WIRE 17 -1 (-5700 2525)(-5700 2425);
WIRE 17 -1 (-5700 2725)(-5700 2525);
WIRE 17 -1 (-5700 2925)(-5700 2725);
WIRE 17 -1 (-5700 3075)(-5700 2925);
WIRE 17 -1 (-5700 3075)(-5700 3275);
WIRE 17 -1 (-5700 3275)(-5700 3475);
WIRE 17 -1 (-5700 3625)(-5700 3475);
WIRE 17 -1 (-5700 3800)(-5700 3625);
WIRE 17 -1 (-5700 3800)(-7225 3800);
FORCEPROP 2 LAST SIG_NAME P3E_CPU1_PE3_MP_RXN<15:8>
J 0
(-7210 3810);
DISPLAY 0.617021 (-7210 3810);
PAINT ORANGE (-7210 3810);
WIRE 17 -1 (-1675 2525)(-1675 2725);
WIRE 17 -1 (-1675 2525)(-1675 2375);
WIRE 17 -1 (-1675 2725)(-1675 2875);
WIRE 17 -1 (-1675 3675)(-1675 2875);
WIRE 17 -1 (-1675 2225)(-1675 2375);
WIRE 17 -1 (-1675 1975)(-1675 2225);
WIRE 17 -1 (-650 3675)(-1675 3675);
FORCEPROP 2 LAST SIG_NAME P3E_CPU1_PE3_MP_TXP<15:8>
J 0
(-1260 3685);
DISPLAY 0.617021 (-1260 3685);
PAINT ORANGE (-1260 3685);
WIRE 17 -1 (-1425 2575)(-1425 2775);
WIRE 17 -1 (-1425 2575)(-1425 2425);
WIRE 17 -1 (-1425 2775)(-1425 2925);
WIRE 17 -1 (-1425 2925)(-1425 3575);
WIRE 17 -1 (-1425 2275)(-1425 2425);
WIRE 17 -1 (-1425 2025)(-1425 2275);
WIRE 17 -1 (-650 3575)(-1425 3575);
FORCEPROP 2 LAST SIG_NAME P3E_CPU1_PE3_MP_TXN<15:8>
J 0
(-1260 3585);
DISPLAY 0.617021 (-1260 3585);
PAINT ORANGE (-1260 3585);
WIRE 17 -1 (-1425 2025)(-1425 1875);
WIRE 17 -1 (-1425 1875)(-1425 1675);
WIRE 17 -1 (-1675 1975)(-1675 1825);
WIRE 17 -1 (-1675 1825)(-1675 1725);
WIRE 16 -1 (-3750 3350)(-3750 3500);
WIRE 16 -1 (-3750 3350)(-3750 3200);
WIRE 16 -1 (-3750 3350)(-3925 3350);
WIRE 16 -1 (-3750 3500)(-3925 3500);
WIRE 16 -1 (-3925 3200)(-3750 3200);
WIRE 16 -1 (-3750 3200)(-3750 3100);
WIRE 16 -1 (-3925 3100)(-3750 3100);
WIRE 16 -1 (-3750 3100)(-3750 2950);
WIRE 16 -1 (-3750 2800)(-3750 2950);
WIRE 16 -1 (-3750 2950)(-3925 2950);
WIRE 16 -1 (-3750 2650)(-3750 2800);
WIRE 16 -1 (-3750 2800)(-3925 2800);
WIRE 16 -1 (-3750 2650)(-3925 2650);
WIRE 16 -1 (-3750 2450)(-3750 2650);
WIRE 16 -1 (-3750 2300)(-3750 2450);
WIRE 16 -1 (-3750 2450)(-3925 2450);
WIRE 16 -1 (-3750 2150)(-3750 2300);
WIRE 16 -1 (-3750 2300)(-3925 2300);
WIRE 16 -1 (-3750 2050)(-3750 2150);
WIRE 16 -1 (-3750 2150)(-3925 2150);
WIRE 16 -1 (-3750 2050)(-3925 2050);
WIRE 16 -1 (-3750 1900)(-3750 2050);
WIRE 16 -1 (-3750 1750)(-3750 1900);
WIRE 16 -1 (-3750 1900)(-3925 1900);
WIRE 16 -1 (-3750 1600)(-3750 1750);
WIRE 16 -1 (-3750 1750)(-3925 1750);
WIRE 16 -1 (-3750 1600)(-3925 1600);
WIRE 16 -1 (-3750 1275)(-3750 1600);
WIRE 16 -1 (-4925 3500)(-5150 3500);
WIRE 16 -1 (-5150 3500)(-5150 3350);
WIRE 16 -1 (-5150 3350)(-4925 3350);
WIRE 16 -1 (-5150 3350)(-5150 3200);
WIRE 16 -1 (-5150 3200)(-4925 3200);
WIRE 16 -1 (-5150 3200)(-5150 3100);
WIRE 16 -1 (-5150 3100)(-4925 3100);
WIRE 16 -1 (-5150 3100)(-5150 2950);
WIRE 16 -1 (-5150 2950)(-4925 2950);
WIRE 16 -1 (-5150 2950)(-5150 2800);
WIRE 16 -1 (-5150 2800)(-4925 2800);
WIRE 16 -1 (-5150 2800)(-5150 2650);
WIRE 16 -1 (-4925 2650)(-5150 2650);
WIRE 16 -1 (-5150 2650)(-5150 2450);
WIRE 16 -1 (-5150 2450)(-4925 2450);
WIRE 16 -1 (-5150 2450)(-5150 2300);
WIRE 16 -1 (-5150 2300)(-4925 2300);
WIRE 16 -1 (-5150 2150)(-5150 2300);
WIRE 16 -1 (-4925 2150)(-5150 2150);
WIRE 16 -1 (-5150 2050)(-5150 2150);
WIRE 16 -1 (-4925 2050)(-5150 2050);
WIRE 16 -1 (-5150 1900)(-5150 2050);
WIRE 16 -1 (-4925 1900)(-5150 1900);
WIRE 16 -1 (-5150 1750)(-5150 1900);
WIRE 16 -1 (-5150 1750)(-4925 1750);
WIRE 16 -1 (-5150 1750)(-5150 1600);
WIRE 16 -1 (-5150 1600)(-4925 1600);
WIRE 16 -1 (-5150 1600)(-5150 1325);
WIRE 16 -1 (-2850 1950)(-1775 1950);
WIRE 16 -1 (-2375 2200)(-1775 2200);
WIRE 16 -1 (-2850 2250)(-1525 2250);
WIRE 16 -1 (-2850 2350)(-1775 2350);
WIRE 16 -1 (-2850 1650)(-1525 1650);
WIRE 16 -1 (-2375 1700)(-1775 1700);
WIRE 16 -1 (-2850 1800)(-1775 1800);
WIRE 16 -1 (-2375 1850)(-1525 1850);
WIRE 16 -1 (-1525 2000)(-2375 2000);
WIRE 16 -1 (-2375 2400)(-1525 2400);
WIRE 16 -1 (-2375 2750)(-1525 2750);
WIRE 16 -1 (-1775 2850)(-2850 2850);
WIRE 16 -1 (-2375 2900)(-1525 2900);
WIRE 16 -1 (-2850 2700)(-1775 2700);
WIRE 16 -1 (-2375 2550)(-1525 2550);
WIRE 16 -1 (-1775 2500)(-2850 2500);
WIRE 16 -1 (-3925 2750)(-2575 2750);
FORCEPROP 2 LAST SIG_NAME P3E_CPU1_PE3_MP_C_TXN<15>
J 0
(-3735 2760);
DISPLAY 0.617021 (-3735 2760);
PAINT ORANGE (-3735 2760);
FORCEPROP 2 LASTPROP $XRERR UNIQUE?
J 0
(-3975 2760);
DISPLAY 0.638298 (-3975 2760);
PAINT MONO (-3975 2760);
DISPLAY INVISIBLE (-3975 2760);
WIRE 16 -1 (-3925 2700)(-3050 2700);
FORCEPROP 2 LAST SIG_NAME P3E_CPU1_PE3_MP_C_TXP<15>
J 0
(-3735 2710);
DISPLAY 0.617021 (-3735 2710);
PAINT ORANGE (-3735 2710);
FORCEPROP 2 LASTPROP $XRERR UNIQUE?
J 0
(-3975 2710);
DISPLAY 0.638298 (-3975 2710);
PAINT MONO (-3975 2710);
DISPLAY INVISIBLE (-3975 2710);
WIRE 16 -1 (-3925 2550)(-2575 2550);
FORCEPROP 2 LAST SIG_NAME P3E_CPU1_PE3_MP_C_TXN<11>
J 0
(-3735 2560);
DISPLAY 0.617021 (-3735 2560);
PAINT ORANGE (-3735 2560);
FORCEPROP 2 LASTPROP $XRERR UNIQUE?
J 0
(-3975 2560);
DISPLAY 0.638298 (-3975 2560);
PAINT MONO (-3975 2560);
DISPLAY INVISIBLE (-3975 2560);
WIRE 16 -1 (-3050 2500)(-3925 2500);
FORCEPROP 2 LAST SIG_NAME P3E_CPU1_PE3_MP_C_TXP<11>
J 0
(-3735 2510);
DISPLAY 0.617021 (-3735 2510);
PAINT ORANGE (-3735 2510);
FORCEPROP 2 LASTPROP $XRERR UNIQUE?
J 0
(-3975 2510);
DISPLAY 0.638298 (-3975 2510);
PAINT MONO (-3975 2510);
DISPLAY INVISIBLE (-3975 2510);
WIRE 16 -1 (-3925 2400)(-2575 2400);
FORCEPROP 2 LAST SIG_NAME P3E_CPU1_PE3_MP_C_TXN<12>
J 0
(-3735 2410);
DISPLAY 0.617021 (-3735 2410);
PAINT ORANGE (-3735 2410);
FORCEPROP 2 LASTPROP $XRERR UNIQUE?
J 0
(-3975 2410);
DISPLAY 0.638298 (-3975 2410);
PAINT MONO (-3975 2410);
DISPLAY INVISIBLE (-3975 2410);
WIRE 16 -1 (-3925 2350)(-3050 2350);
FORCEPROP 2 LAST SIG_NAME P3E_CPU1_PE3_MP_C_TXP<12>
J 0
(-3735 2360);
DISPLAY 0.617021 (-3735 2360);
PAINT ORANGE (-3735 2360);
FORCEPROP 2 LASTPROP $XRERR UNIQUE?
J 0
(-3975 2360);
DISPLAY 0.638298 (-3975 2360);
PAINT MONO (-3975 2360);
DISPLAY INVISIBLE (-3975 2360);
WIRE 16 -1 (-3925 2250)(-3050 2250);
FORCEPROP 2 LAST SIG_NAME P3E_CPU1_PE3_MP_C_TXN<13>
J 0
(-3735 2260);
DISPLAY 0.617021 (-3735 2260);
PAINT ORANGE (-3735 2260);
FORCEPROP 2 LASTPROP $XRERR UNIQUE?
J 0
(-3975 2260);
DISPLAY 0.638298 (-3975 2260);
PAINT MONO (-3975 2260);
DISPLAY INVISIBLE (-3975 2260);
WIRE 16 -1 (-3925 2200)(-2575 2200);
FORCEPROP 2 LAST SIG_NAME P3E_CPU1_PE3_MP_C_TXP<13>
J 0
(-3735 2210);
DISPLAY 0.617021 (-3735 2210);
PAINT ORANGE (-3735 2210);
FORCEPROP 2 LASTPROP $XRERR UNIQUE?
J 0
(-3975 2210);
DISPLAY 0.638298 (-3975 2210);
PAINT MONO (-3975 2210);
DISPLAY INVISIBLE (-3975 2210);
WIRE 16 -1 (-2825 3600)(-3925 3600);
FORCEPROP 0 LAST SIG_NAME TP_IOA5
J 0
(-3560 3610);
DISPLAY 0.617021 (-3560 3610);
PAINT ORANGE (-3560 3610);
FORCEPROP 2 LASTPROP $XRERR UNIQUE?
J 0
(-2795 3600);
DISPLAY 0.638298 (-2795 3600);
PAINT MONO (-2795 3600);
DISPLAY INVISIBLE (-2795 3600);
WIRE 16 -1 (-3925 2900)(-2575 2900);
FORCEPROP 2 LAST SIG_NAME P3E_CPU1_PE3_MP_C_TXN<14>
J 0
(-3735 2910);
DISPLAY 0.617021 (-3735 2910);
PAINT ORANGE (-3735 2910);
FORCEPROP 2 LASTPROP $XRERR UNIQUE?
J 0
(-3975 2910);
DISPLAY 0.638298 (-3975 2910);
PAINT MONO (-3975 2910);
DISPLAY INVISIBLE (-3975 2910);
WIRE 16 -1 (-3050 2850)(-3925 2850);
FORCEPROP 2 LAST SIG_NAME P3E_CPU1_PE3_MP_C_TXP<14>
J 0
(-3735 2860);
DISPLAY 0.617021 (-3735 2860);
PAINT ORANGE (-3735 2860);
FORCEPROP 2 LASTPROP $XRERR UNIQUE?
J 0
(-3975 2860);
DISPLAY 0.638298 (-3975 2860);
PAINT MONO (-3975 2860);
DISPLAY INVISIBLE (-3975 2860);
WIRE 16 -1 (-2825 3400)(-3925 3400);
FORCEPROP 2 LAST SIG_NAME SMB_LAN_STBY_LVC3_SCL
J 0
(-3575 3410);
DISPLAY 0.617021 (-3575 3410);
PAINT ORANGE (-3575 3410);
WIRE 16 -1 (-3925 3450)(-2825 3450);
FORCEPROP 2 LAST SIG_NAME SMB_LAN_STBY_LVC3_SDA
J 0
(-3575 3460);
DISPLAY 0.617021 (-3575 3460);
PAINT ORANGE (-3575 3460);
WIRE 16 -1 (-2825 3550)(-3925 3550);
FORCEPROP 2 LAST SIG_NAME IRQ_BOARD_BMC_ALERT_N
J 0
(-3560 3560);
DISPLAY 0.617021 (-3560 3560);
PAINT ORANGE (-3560 3560);
WIRE 16 -1 (-2850 3300)(-3925 3300);
FORCEPROP 2 LAST SIG_NAME FM_XRC_PRESENT_N
J 0
(-3575 3310);
DISPLAY 0.617021 (-3575 3310);
PAINT ORANGE (-3575 3310);
WIRE 16 -1 (-3925 3250)(-2850 3250);
FORCEPROP 2 LAST SIG_NAME FM_XRC_READY_N
J 0
(-3575 3260);
DISPLAY 0.617021 (-3575 3260);
PAINT ORANGE (-3575 3260);
WIRE 16 -1 (-3925 3050)(-2850 3050);
FORCEPROP 2 LAST SIG_NAME SMB_PEHPCPU1_STBY_LVC3_SDA
J 0
(-3460 3060);
DISPLAY 0.617021 (-3460 3060);
PAINT ORANGE (-3460 3060);
WIRE 16 -1 (-3925 3000)(-2850 3000);
FORCEPROP 2 LAST SIG_NAME SMB_PEHPCPU1_STBY_LVC3_SCL
J 0
(-3460 3010);
DISPLAY 0.617021 (-3460 3010);
PAINT ORANGE (-3460 3010);
WIRE 16 -1 (-3925 1950)(-3050 1950);
FORCEPROP 2 LAST SIG_NAME P3E_CPU1_PE3_MP_C_TXP<8>
J 0
(-3735 1960);
DISPLAY 0.617021 (-3735 1960);
PAINT ORANGE (-3735 1960);
FORCEPROP 2 LASTPROP $XRERR UNIQUE?
J 0
(-3975 1960);
DISPLAY 0.638298 (-3975 1960);
PAINT MONO (-3975 1960);
DISPLAY INVISIBLE (-3975 1960);
WIRE 16 -1 (-3925 1850)(-2575 1850);
FORCEPROP 2 LAST SIG_NAME P3E_CPU1_PE3_MP_C_TXN<9>
J 0
(-3735 1860);
DISPLAY 0.617021 (-3735 1860);
PAINT ORANGE (-3735 1860);
FORCEPROP 2 LASTPROP $XRERR UNIQUE?
J 0
(-3975 1860);
DISPLAY 0.638298 (-3975 1860);
PAINT MONO (-3975 1860);
DISPLAY INVISIBLE (-3975 1860);
WIRE 16 -1 (-3925 1800)(-3050 1800);
FORCEPROP 2 LAST SIG_NAME P3E_CPU1_PE3_MP_C_TXP<9>
J 0
(-3735 1810);
DISPLAY 0.617021 (-3735 1810);
PAINT ORANGE (-3735 1810);
FORCEPROP 2 LASTPROP $XRERR UNIQUE?
J 0
(-3975 1810);
DISPLAY 0.638298 (-3975 1810);
PAINT MONO (-3975 1810);
DISPLAY INVISIBLE (-3975 1810);
WIRE 16 -1 (-3925 1700)(-2575 1700);
FORCEPROP 2 LAST SIG_NAME P3E_CPU1_PE3_MP_C_TXP<10>
J 0
(-3735 1710);
DISPLAY 0.617021 (-3735 1710);
PAINT ORANGE (-3735 1710);
FORCEPROP 2 LASTPROP $XRERR UNIQUE?
J 0
(-3975 1710);
DISPLAY 0.638298 (-3975 1710);
PAINT MONO (-3975 1710);
DISPLAY INVISIBLE (-3975 1710);
WIRE 16 -1 (-2575 2000)(-3925 2000);
FORCEPROP 2 LAST SIG_NAME P3E_CPU1_PE3_MP_C_TXN<8>
J 0
(-3735 2010);
DISPLAY 0.617021 (-3735 2010);
PAINT ORANGE (-3735 2010);
FORCEPROP 2 LASTPROP $XRERR UNIQUE?
J 0
(-3975 2010);
DISPLAY 0.638298 (-3975 2010);
PAINT MONO (-3975 2010);
DISPLAY INVISIBLE (-3975 2010);
WIRE 16 -1 (-3925 1650)(-3050 1650);
FORCEPROP 2 LAST SIG_NAME P3E_CPU1_PE3_MP_C_TXN<10>
J 0
(-3735 1660);
DISPLAY 0.617021 (-3735 1660);
PAINT ORANGE (-3735 1660);
FORCEPROP 2 LASTPROP $XRERR UNIQUE?
J 0
(-3975 1660);
DISPLAY 0.638298 (-3975 1660);
PAINT MONO (-3975 1660);
DISPLAY INVISIBLE (-3975 1660);
WIRE 16 -1 (-4925 2700)(-5600 2700);
WIRE 16 -1 (-4925 2750)(-5350 2750);
WIRE 16 -1 (-4925 2850)(-5350 2850);
WIRE 16 -1 (-4925 2900)(-5600 2900);
WIRE 16 -1 (-4925 3050)(-5600 3050);
WIRE 16 -1 (-4925 3000)(-5350 3000);
WIRE 16 -1 (-4925 3400)(-5350 3400);
WIRE 16 -1 (-4925 3450)(-5600 3450);
WIRE 16 -1 (-4925 3550)(-5350 3550);
WIRE 16 -1 (-4925 3600)(-5600 3600);
WIRE 16 -1 (-4925 2500)(-5600 2500);
WIRE 16 -1 (-4925 3300)(-5350 3300);
WIRE 16 -1 (-4925 3250)(-5600 3250);
WIRE 16 -1 (-4925 2550)(-5350 2550);
WIRE 16 -1 (-4925 2400)(-5600 2400);
WIRE 16 -1 (-4925 2350)(-5350 2350);
WIRE 16 3135 (-7950 275)(-5200 275);
WIRE 16 3135 (-7950 1500)(-7950 275);
WIRE 16 3135 (-5200 275)(-5200 1100);
WIRE 16 3135 (-5200 1100)(-5700 1100);
WIRE 16 3135 (-5700 1500)(-7950 1500);
WIRE 16 3135 (-5700 1100)(-5700 1500);
WIRE 16 -1 (-4925 2000)(-6350 2000);
FORCEPROP 0 LAST SIG_NAME TP_FM_WAKE_N
J 0
(-6335 2010);
DISPLAY 0.617021 (-6335 2010);
PAINT ORANGE (-6335 2010);
FORCEPROP 2 LASTPROP $XRERR UNIQUE?
J 0
(-6590 2000);
DISPLAY 0.638298 (-6590 2000);
PAINT MONO (-6590 2000);
DISPLAY INVISIBLE (-6590 2000);
WIRE 16 -1 (-4925 2250)(-6350 2250);
FORCEPROP 0 LAST SIG_NAME TP_IOG3
J 0
(-6285 2260);
DISPLAY 0.617021 (-6285 2260);
PAINT ORANGE (-6285 2260);
FORCEPROP 2 LASTPROP $XRERR UNIQUE?
J 0
(-6590 2250);
DISPLAY 0.638298 (-6590 2250);
PAINT MONO (-6590 2250);
DISPLAY INVISIBLE (-6590 2250);
WIRE 16 -1 (-4925 2200)(-6350 2200);
FORCEPROP 0 LAST SIG_NAME TP_IOH3
J 0
(-6285 2210);
DISPLAY 0.617021 (-6285 2210);
PAINT ORANGE (-6285 2210);
FORCEPROP 2 LASTPROP $XRERR UNIQUE?
J 0
(-6590 2200);
DISPLAY 0.638298 (-6590 2200);
PAINT MONO (-6590 2200);
DISPLAY INVISIBLE (-6590 2200);
WIRE 16 -1 (-6350 1850)(-4925 1850);
FORCEPROP 0 LAST SIG_NAME TP_IOE4
J 0
(-6310 1860);
DISPLAY 0.617021 (-6310 1860);
PAINT ORANGE (-6310 1860);
FORCEPROP 2 LASTPROP $XRERR UNIQUE?
J 0
(-6590 1850);
DISPLAY 0.638298 (-6590 1850);
PAINT MONO (-6590 1850);
DISPLAY INVISIBLE (-6590 1850);
WIRE 16 -1 (-6350 1800)(-4925 1800);
FORCEPROP 0 LAST SIG_NAME TP_IOF4
J 0
(-6310 1810);
DISPLAY 0.617021 (-6310 1810);
PAINT ORANGE (-6310 1810);
FORCEPROP 2 LASTPROP $XRERR UNIQUE?
J 0
(-6590 1800);
DISPLAY 0.638298 (-6590 1800);
PAINT MONO (-6590 1800);
DISPLAY INVISIBLE (-6590 1800);
WIRE 16 -1 (-4925 1700)(-6350 1700);
FORCEPROP 0 LAST SIG_NAME TP_IOH4
J 0
(-6310 1710);
DISPLAY 0.617021 (-6310 1710);
PAINT ORANGE (-6310 1710);
FORCEPROP 2 LASTPROP $XRERR UNIQUE?
J 0
(-6590 1700);
DISPLAY 0.638298 (-6590 1700);
PAINT MONO (-6590 1700);
DISPLAY INVISIBLE (-6590 1700);
WIRE 16 -1 (-4925 1650)(-6350 1650);
FORCEPROP 0 LAST SIG_NAME TP_IOI4
J 0
(-6310 1660);
DISPLAY 0.617021 (-6310 1660);
PAINT ORANGE (-6310 1660);
FORCEPROP 2 LASTPROP $XRERR UNIQUE?
J 0
(-6590 1650);
DISPLAY 0.638298 (-6590 1650);
PAINT MONO (-6590 1650);
DISPLAY INVISIBLE (-6590 1650);
WIRE 16 -1 (-6450 750)(-5575 750);
FORCEPROP 2 LAST SIG_NAME FAN_TACH3_R
J 2
(-5550 760);
DISPLAY 0.617021 (-5550 760);
PAINT ORANGE (-5550 760);
WIRE 16 -1 (-6450 625)(-5575 625);
FORCEPROP 2 LAST SIG_NAME FAN_TACH2_R
J 2
(-5550 635);
DISPLAY 0.617021 (-5550 635);
PAINT ORANGE (-5550 635);
WIRE 16 -1 (-6450 500)(-5575 500);
FORCEPROP 2 LAST SIG_NAME FAN_PWM_OUT_SYS0_R1
J 2
(-5550 510);
DISPLAY 0.617021 (-5550 510);
PAINT ORANGE (-5550 510);
WIRE 16 -1 (-6450 350)(-5575 350);
FORCEPROP 2 LAST SIG_NAME FAN_TACH0_R
J 2
(-5550 360);
DISPLAY 0.617021 (-5550 360);
PAINT ORANGE (-5550 360);
WIRE 16 -1 (-4925 1950)(-6350 1950);
FORCEPROP 0 LAST SIG_NAME FM_BB_BMC_MP_GPIO
J 0
(-6335 1960);
DISPLAY 0.617021 (-6335 1960);
PAINT ORANGE (-6335 1960);
WIRE 16 -1 (-6450 875)(-5575 875);
FORCEPROP 2 LAST SIG_NAME FAN_TACH1_R
J 2
(-5550 885);
DISPLAY 0.617021 (-5550 885);
PAINT ORANGE (-5550 885);
WIRE 16 -1 (-7375 750)(-6650 750);
FORCEPROP 2 LAST SIG_NAME SMB_LAN_STBY_LVC3_SDA
J 0
(-7400 760);
DISPLAY 0.617021 (-7400 760);
PAINT ORANGE (-7400 760);
WIRE 16 -1 (-7375 625)(-6650 625);
FORCEPROP 2 LAST SIG_NAME IRQ_BOARD_BMC_ALERT_N
J 0
(-7400 635);
DISPLAY 0.617021 (-7400 635);
PAINT ORANGE (-7400 635);
WIRE 16 -1 (-7375 500)(-6650 500);
FORCEPROP 2 LAST SIG_NAME FM_BMC_READY_N
J 0
(-7400 510);
DISPLAY 0.617021 (-7400 510);
PAINT ORANGE (-7400 510);
WIRE 16 -1 (-7375 350)(-6650 350);
FORCEPROP 2 LAST SIG_NAME FM_XRC_READY_N
J 0
(-7400 360);
DISPLAY 0.617021 (-7400 360);
PAINT ORANGE (-7400 360);
WIRE 16 -1 (-7375 875)(-6650 875);
FORCEPROP 2 LAST SIG_NAME SMB_LAN_STBY_LVC3_SCL
J 0
(-7400 885);
DISPLAY 0.617021 (-7400 885);
PAINT ORANGE (-7400 885);
DOT 1 (-5150 1600);
DOT 1 (-5150 1750);
DOT 1 (-5150 1900);
DOT 1 (-5150 2050);
DOT 1 (-5150 2150);
DOT 1 (-5150 2300);
DOT 1 (-5150 2450);
DOT 1 (-5150 2650);
DOT 1 (-5150 2800);
DOT 1 (-5150 2950);
DOT 1 (-5150 3200);
DOT 1 (-5150 3100);
DOT 1 (-5150 3350);
DOT 1 (-3750 1600);
DOT 1 (-3750 1750);
DOT 1 (-3750 1900);
DOT 1 (-3750 2050);
DOT 1 (-3750 2150);
DOT 1 (-3750 2300);
DOT 1 (-3750 2450);
DOT 1 (-3750 2800);
DOT 1 (-3750 2650);
DOT 1 (-3750 2950);
DOT 1 (-3750 3100);
DOT 1 (-3750 3200);
DOT 1 (-3750 3350);
FORCENOTE
ROOM: IO_SLOT
(-7869 189) 0;
DISPLAY LEFT (-7869 189);
DISPLAY 1.021277 (-7869 189);
PAINT PURPLE (-7869 189);
FORCENOTE
CAD NOTE:
(-3275 1475) 0;
DISPLAY LEFT (-3275 1475);
DISPLAY 1.021277 (-3275 1475);
PAINT PURPLE (-3275 1475);
FORCENOTE
PLACE CAPS NEAR MID-PLANE CONNECTOR
(-3275 1400) 0;
DISPLAY LEFT (-3275 1400);
DISPLAY 1.021277 (-3275 1400);
PAINT PURPLE (-3275 1400);
QUIT
